FILE_TYPE = MACRO_DRAWING;
SET COLOR_WIRE YELLOW;
SET COLOR_PROP ORANGE;
SET COLOR_DOT WHITE;
SET COLOR_ARC YELLOW;
SET COLOR_BODY GREEN;
SET COLOR_NOTE PURPLE;
SET PROP_DISPLAY VALUE;
SET PAGE_NUMBER P450;
FORCEADD OFFPAGE..1
(-4250 2200);
FORCEPROP 2 LAST $XR0 342 
J 0
(-4502 2200);
DISPLAY 0.638298 (-4502 2200);
PAINT MONO (-4502 2200);
FORCEPROP 2 LAST CDS_LIB standard
J 0
(-4250 2200);
DISPLAY INVISIBLE (-4250 2200);
FORCEPROP 1 LAST OFFPAGE TRUE
J 0
(-3925 2075);
DISPLAY 0.872340 (-3925 2075);
DISPLAY INVISIBLE (-3925 2075);
FORCEPROP 1 LAST COMMENT_BODY TRUE
J 0
(-4125 2100);
DISPLAY 0.872340 (-4125 2100);
PAINT GREEN (-4125 2100);
DISPLAY INVISIBLE (-4125 2100);
FORCEPROP 2 LAST PATH I1
J 0
(-4500 2250);
DISPLAY 0.680851 (-4500 2250);
DISPLAY INVISIBLE (-4500 2250);
FORCEADD TAP..1
R 2
(-3050 1375);
FORCEPROP 3 LASTPIN (-3000 1375) SIG_NAME P5E_CPU1_P2_TX_BUF_DP<4>
J 0
(-2990 1385);
DISPLAY 0.659574 (-2990 1385);
PAINT MONO (-2990 1385);
DISPLAY INVISIBLE (-2990 1385);
FORCEPROP 1 LASTPIN (-3000 1375) BN 4
J 2
(-2988 1383);
DISPLAY 0.680851 (-2988 1383);
PAINT GREEN (-2988 1383);
FORCEPROP 2 LAST CDS_LIB standard
J 0
(-3050 1375);
DISPLAY INVISIBLE (-3050 1375);
FORCEPROP 1 LAST BODY_TYPE PLUMBING
J 2
(-3050 1425);
DISPLAY 0.872340 (-3050 1425);
PAINT GREEN (-3050 1425);
DISPLAY INVISIBLE (-3050 1425);
FORCEPROP 1 LAST HDL_TAP TRUE
J 2
(-3375 1250);
DISPLAY 0.872340 (-3375 1250);
DISPLAY INVISIBLE (-3375 1250);
FORCEPROP 1 LAST PATH I10
J 2
(-3048 1375);
DISPLAY 0.872340 (-3048 1375);
PAINT GREEN (-3048 1375);
DISPLAY INVISIBLE (-3048 1375);
FORCEADD TAP..1
R 2
(-8075 2200);
FORCEPROP 3 LASTPIN (-8025 2200) SIG_NAME P5E_CPU1_P2_TX_BUF_DN<8>
J 0
(-8015 2210);
DISPLAY 0.659574 (-8015 2210);
PAINT MONO (-8015 2210);
DISPLAY INVISIBLE (-8015 2210);
FORCEPROP 1 LASTPIN (-8025 2200) BN 8
J 2
(-8013 2208);
DISPLAY 0.680851 (-8013 2208);
PAINT GREEN (-8013 2208);
FORCEPROP 2 LAST CDS_LIB standard
J 0
(-8075 2200);
DISPLAY INVISIBLE (-8075 2200);
FORCEPROP 1 LAST BODY_TYPE PLUMBING
J 2
(-8075 2250);
DISPLAY 0.872340 (-8075 2250);
PAINT GREEN (-8075 2250);
DISPLAY INVISIBLE (-8075 2250);
FORCEPROP 1 LAST HDL_TAP TRUE
J 2
(-8400 2075);
DISPLAY 0.872340 (-8400 2075);
DISPLAY INVISIBLE (-8400 2075);
FORCEPROP 1 LAST PATH I100
J 2
(-8073 2200);
DISPLAY 0.872340 (-8073 2200);
PAINT GREEN (-8073 2200);
DISPLAY INVISIBLE (-8073 2200);
FORCEADD TAP..1
R 2
(-7825 2250);
FORCEPROP 3 LASTPIN (-7775 2250) SIG_NAME P5E_CPU1_P2_TX_BUF_DP<8>
J 0
(-7765 2260);
DISPLAY 0.659574 (-7765 2260);
PAINT MONO (-7765 2260);
DISPLAY INVISIBLE (-7765 2260);
FORCEPROP 1 LASTPIN (-7775 2250) BN 8
J 2
(-7763 2258);
DISPLAY 0.680851 (-7763 2258);
PAINT GREEN (-7763 2258);
FORCEPROP 2 LAST CDS_LIB standard
J 0
(-7825 2250);
DISPLAY INVISIBLE (-7825 2250);
FORCEPROP 1 LAST BODY_TYPE PLUMBING
J 2
(-7825 2300);
DISPLAY 0.872340 (-7825 2300);
PAINT GREEN (-7825 2300);
DISPLAY INVISIBLE (-7825 2300);
FORCEPROP 1 LAST HDL_TAP TRUE
J 2
(-8150 2125);
DISPLAY 0.872340 (-8150 2125);
DISPLAY INVISIBLE (-8150 2125);
FORCEPROP 1 LAST PATH I101
J 2
(-7823 2250);
DISPLAY 0.872340 (-7823 2250);
PAINT GREEN (-7823 2250);
DISPLAY INVISIBLE (-7823 2250);
FORCEADD Q_CAP_DIFFBUS..2
R 2
(-7100 2250);
FORCEPROP 1 LAST LOCATION C6709
J 2
(-6825 2250);
DISPLAY 0.723404 (-6825 2250);
PAINT GREEN (-6825 2250);
FORCEPROP 2 LAST $SEC 1
J 2
(-6925 2325);
DISPLAY 0.680851 (-6925 2325);
PAINT MONO (-6925 2325);
DISPLAY INVISIBLE (-6925 2325);
FORCEPROP 2 LAST CDS_SEC 1
J 2
(-6925 2325);
DISPLAY 0.680851 (-6925 2325);
DISPLAY INVISIBLE (-6925 2325);
FORCEPROP 2 LASTPIN (-7025 2250) $PN 1
J 0
(-7015 2260);
DISPLAY 0.808511 (-7015 2260);
FORCEPROP 2 LASTPIN (-7175 2250) $PN 2
J 2
(-7185 2260);
DISPLAY 0.808511 (-7185 2260);
FORCEPROP 2 LAST VALUE DIFF BUS_0.22UF
J 2
(-7250 2250);
DISPLAY 0.553191 (-7250 2250);
FORCEPROP 2 LAST VOLTAGE 6.3V
J 2
(-6925 2400);
DISPLAY 0.553191 (-6925 2400);
PAINT GREEN (-6925 2400);
FORCEPROP 1 LAST MATERIAL X6S
J 2
(-7191 2454);
DISPLAY 0.574468 (-7191 2454);
PAINT GREEN (-7191 2454);
FORCEPROP 2 LAST PACK_TYPE C0201
J 2
(-7150 2400);
DISPLAY 0.553191 (-7150 2400);
PAINT GREEN (-7150 2400);
FORCEPROP 2 LAST TOLERANCE 20%
J 2
(-7050 2400);
DISPLAY 0.553191 (-7050 2400);
PAINT GREEN (-7050 2400);
FORCEPROP 2 LAST CDS_LIB pure_quanta
J 2
(-7100 2250);
DISPLAY INVISIBLE (-7100 2250);
FORCEPROP 1 LAST CDS_LMAN_SYM_OUTLINE -25,50,25,-50
J 2
(-7100 2250);
DISPLAY 0.468085 (-7100 2250);
PAINT GREEN (-7100 2250);
DISPLAY INVISIBLE (-7100 2250);
FORCEPROP 1 LAST PIN_NAMES_ROTATE TRUE
J 2
(-7100 2250);
DISPLAY 0.489362 (-7100 2250);
PAINT GREEN (-7100 2250);
DISPLAY INVISIBLE (-7100 2250);
FORCEPROP 1 LAST PATH I102
J 2
(-7100 2250);
DISPLAY 0.723404 (-7100 2250);
DISPLAY INVISIBLE (-7100 2250);
FORCEPROP 1 LAST PART_NUMBER SP_CH4221MEE01
J 2
(-6916 2338);
DISPLAY 0.574468 (-6916 2338);
PAINT GREEN (-6916 2338);
DISPLAY INVISIBLE (-6916 2338);
FORCEPROP 1 LAST LOCATION C6709
J 0
(-6850 2325);
DISPLAY 1.021277 (-6850 2325);
DISPLAY INVISIBLE (-6850 2325);
FORCEADD Q_CAP_DIFFBUS..2
R 2
(-7100 2200);
FORCEPROP 1 LAST LOCATION C6710
J 2
(-6825 2200);
DISPLAY 0.723404 (-6825 2200);
PAINT GREEN (-6825 2200);
FORCEPROP 2 LAST $SEC 1
J 2
(-6925 2275);
DISPLAY 0.680851 (-6925 2275);
PAINT MONO (-6925 2275);
DISPLAY INVISIBLE (-6925 2275);
FORCEPROP 2 LAST CDS_SEC 1
J 2
(-6925 2275);
DISPLAY 0.680851 (-6925 2275);
DISPLAY INVISIBLE (-6925 2275);
FORCEPROP 2 LASTPIN (-7025 2200) $PN 1
J 0
(-7015 2210);
DISPLAY 0.808511 (-7015 2210);
FORCEPROP 2 LASTPIN (-7175 2200) $PN 2
J 2
(-7185 2210);
DISPLAY 0.808511 (-7185 2210);
FORCEPROP 2 LAST VALUE DIFF BUS_0.22UF
J 2
(-7250 2200);
DISPLAY 0.553191 (-7250 2200);
FORCEPROP 1 LAST CDS_LMAN_SYM_OUTLINE -25,50,25,-50
J 2
(-7100 2200);
DISPLAY 0.468085 (-7100 2200);
PAINT GREEN (-7100 2200);
DISPLAY INVISIBLE (-7100 2200);
FORCEPROP 2 LAST CDS_LIB pure_quanta
J 2
(-7100 2200);
DISPLAY INVISIBLE (-7100 2200);
FORCEPROP 1 LAST PIN_NAMES_ROTATE TRUE
J 2
(-7100 2200);
DISPLAY 0.489362 (-7100 2200);
PAINT GREEN (-7100 2200);
DISPLAY INVISIBLE (-7100 2200);
FORCEPROP 2 LAST VOLTAGE 6.3V
J 2
(-7450 2250);
DISPLAY 0.553191 (-7450 2250);
DISPLAY INVISIBLE (-7450 2250);
FORCEPROP 1 LAST MATERIAL X6S
J 2
(-7091 2279);
DISPLAY 0.574468 (-7091 2279);
PAINT GREEN (-7091 2279);
DISPLAY INVISIBLE (-7091 2279);
FORCEPROP 2 LAST PACK_TYPE C0201
J 2
(-7275 2250);
DISPLAY 0.553191 (-7275 2250);
DISPLAY INVISIBLE (-7275 2250);
FORCEPROP 2 LAST TOLERANCE 20%
J 2
(-7175 2250);
DISPLAY 0.553191 (-7175 2250);
DISPLAY INVISIBLE (-7175 2250);
FORCEPROP 1 LAST PATH I103
J 2
(-7100 2200);
DISPLAY 0.723404 (-7100 2200);
DISPLAY INVISIBLE (-7100 2200);
FORCEPROP 1 LAST PART_NUMBER SP_CH4221MEE01
J 2
(-7216 2288);
DISPLAY 0.574468 (-7216 2288);
PAINT GREEN (-7216 2288);
DISPLAY INVISIBLE (-7216 2288);
FORCEPROP 1 LAST LOCATION C6710
J 0
(-6850 2275);
DISPLAY 1.021277 (-6850 2275);
DISPLAY INVISIBLE (-6850 2275);
FORCEADD TAP..1
(-6550 850);
FORCEPROP 3 LASTPIN (-6600 850) SIG_NAME P5E_CPU1_P2_TX_BUF_C_DP<15>
J 0
(-6590 860);
DISPLAY 0.659574 (-6590 860);
PAINT MONO (-6590 860);
DISPLAY INVISIBLE (-6590 860);
FORCEPROP 1 LASTPIN (-6600 850) BN 15
J 0
(-6612 858);
DISPLAY 0.680851 (-6612 858);
PAINT GREEN (-6612 858);
FORCEPROP 2 LAST CDS_LIB standard
J 0
(-6550 850);
DISPLAY INVISIBLE (-6550 850);
FORCEPROP 1 LAST BODY_TYPE PLUMBING
J 0
(-6550 900);
DISPLAY 0.872340 (-6550 900);
PAINT GREEN (-6550 900);
DISPLAY INVISIBLE (-6550 900);
FORCEPROP 1 LAST HDL_TAP TRUE
J 0
(-6225 725);
DISPLAY 0.872340 (-6225 725);
DISPLAY INVISIBLE (-6225 725);
FORCEPROP 1 LAST PATH I104
J 0
(-6552 850);
DISPLAY 0.872340 (-6552 850);
PAINT GREEN (-6552 850);
DISPLAY INVISIBLE (-6552 850);
FORCEADD TAP..1
(-6550 1050);
FORCEPROP 3 LASTPIN (-6600 1050) SIG_NAME P5E_CPU1_P2_TX_BUF_C_DP<14>
J 0
(-6590 1060);
DISPLAY 0.659574 (-6590 1060);
PAINT MONO (-6590 1060);
DISPLAY INVISIBLE (-6590 1060);
FORCEPROP 1 LASTPIN (-6600 1050) BN 14
J 0
(-6612 1058);
DISPLAY 0.680851 (-6612 1058);
PAINT GREEN (-6612 1058);
FORCEPROP 2 LAST CDS_LIB standard
J 0
(-6550 1050);
DISPLAY INVISIBLE (-6550 1050);
FORCEPROP 1 LAST BODY_TYPE PLUMBING
J 0
(-6550 1100);
DISPLAY 0.872340 (-6550 1100);
PAINT GREEN (-6550 1100);
DISPLAY INVISIBLE (-6550 1100);
FORCEPROP 1 LAST HDL_TAP TRUE
J 0
(-6225 925);
DISPLAY 0.872340 (-6225 925);
DISPLAY INVISIBLE (-6225 925);
FORCEPROP 1 LAST PATH I105
J 0
(-6552 1050);
DISPLAY 0.872340 (-6552 1050);
PAINT GREEN (-6552 1050);
DISPLAY INVISIBLE (-6552 1050);
FORCEADD TAP..1
(-6350 800);
FORCEPROP 3 LASTPIN (-6400 800) SIG_NAME P5E_CPU1_P2_TX_BUF_C_DN<15>
J 0
(-6390 810);
DISPLAY 0.659574 (-6390 810);
PAINT MONO (-6390 810);
DISPLAY INVISIBLE (-6390 810);
FORCEPROP 1 LASTPIN (-6400 800) BN 15
J 0
(-6412 808);
DISPLAY 0.680851 (-6412 808);
PAINT GREEN (-6412 808);
FORCEPROP 2 LAST CDS_LIB standard
J 0
(-6350 800);
DISPLAY INVISIBLE (-6350 800);
FORCEPROP 1 LAST BODY_TYPE PLUMBING
J 0
(-6350 850);
DISPLAY 0.872340 (-6350 850);
PAINT GREEN (-6350 850);
DISPLAY INVISIBLE (-6350 850);
FORCEPROP 1 LAST HDL_TAP TRUE
J 0
(-6025 675);
DISPLAY 0.872340 (-6025 675);
DISPLAY INVISIBLE (-6025 675);
FORCEPROP 1 LAST PATH I106
J 0
(-6352 800);
DISPLAY 0.872340 (-6352 800);
PAINT GREEN (-6352 800);
DISPLAY INVISIBLE (-6352 800);
FORCEADD TAP..1
(-6350 1000);
FORCEPROP 3 LASTPIN (-6400 1000) SIG_NAME P5E_CPU1_P2_TX_BUF_C_DN<14>
J 0
(-6390 1010);
DISPLAY 0.659574 (-6390 1010);
PAINT MONO (-6390 1010);
DISPLAY INVISIBLE (-6390 1010);
FORCEPROP 1 LASTPIN (-6400 1000) BN 14
J 0
(-6412 1008);
DISPLAY 0.680851 (-6412 1008);
PAINT GREEN (-6412 1008);
FORCEPROP 2 LAST CDS_LIB standard
J 0
(-6350 1000);
DISPLAY INVISIBLE (-6350 1000);
FORCEPROP 1 LAST BODY_TYPE PLUMBING
J 0
(-6350 1050);
DISPLAY 0.872340 (-6350 1050);
PAINT GREEN (-6350 1050);
DISPLAY INVISIBLE (-6350 1050);
FORCEPROP 1 LAST HDL_TAP TRUE
J 0
(-6025 875);
DISPLAY 0.872340 (-6025 875);
DISPLAY INVISIBLE (-6025 875);
FORCEPROP 1 LAST PATH I107
J 0
(-6352 1000);
DISPLAY 0.872340 (-6352 1000);
PAINT GREEN (-6352 1000);
DISPLAY INVISIBLE (-6352 1000);
FORCEADD TAP..1
(-6550 1250);
FORCEPROP 3 LASTPIN (-6600 1250) SIG_NAME P5E_CPU1_P2_TX_BUF_C_DP<13>
J 0
(-6590 1260);
DISPLAY 0.659574 (-6590 1260);
PAINT MONO (-6590 1260);
DISPLAY INVISIBLE (-6590 1260);
FORCEPROP 1 LASTPIN (-6600 1250) BN 13
J 0
(-6612 1258);
DISPLAY 0.680851 (-6612 1258);
PAINT GREEN (-6612 1258);
FORCEPROP 2 LAST CDS_LIB standard
J 0
(-6550 1250);
DISPLAY INVISIBLE (-6550 1250);
FORCEPROP 1 LAST BODY_TYPE PLUMBING
J 0
(-6550 1300);
DISPLAY 0.872340 (-6550 1300);
PAINT GREEN (-6550 1300);
DISPLAY INVISIBLE (-6550 1300);
FORCEPROP 1 LAST HDL_TAP TRUE
J 0
(-6225 1125);
DISPLAY 0.872340 (-6225 1125);
DISPLAY INVISIBLE (-6225 1125);
FORCEPROP 1 LAST PATH I108
J 0
(-6552 1250);
DISPLAY 0.872340 (-6552 1250);
PAINT GREEN (-6552 1250);
DISPLAY INVISIBLE (-6552 1250);
FORCEADD TAP..1
(-6550 1450);
FORCEPROP 3 LASTPIN (-6600 1450) SIG_NAME P5E_CPU1_P2_TX_BUF_C_DP<12>
J 0
(-6590 1460);
DISPLAY 0.659574 (-6590 1460);
PAINT MONO (-6590 1460);
DISPLAY INVISIBLE (-6590 1460);
FORCEPROP 1 LASTPIN (-6600 1450) BN 12
J 0
(-6612 1458);
DISPLAY 0.680851 (-6612 1458);
PAINT GREEN (-6612 1458);
FORCEPROP 2 LAST CDS_LIB standard
J 0
(-6550 1450);
DISPLAY INVISIBLE (-6550 1450);
FORCEPROP 1 LAST BODY_TYPE PLUMBING
J 0
(-6550 1500);
DISPLAY 0.872340 (-6550 1500);
PAINT GREEN (-6550 1500);
DISPLAY INVISIBLE (-6550 1500);
FORCEPROP 1 LAST HDL_TAP TRUE
J 0
(-6225 1325);
DISPLAY 0.872340 (-6225 1325);
DISPLAY INVISIBLE (-6225 1325);
FORCEPROP 1 LAST PATH I109
J 0
(-6552 1450);
DISPLAY 0.872340 (-6552 1450);
PAINT GREEN (-6552 1450);
DISPLAY INVISIBLE (-6552 1450);
FORCEADD TAP..1
R 2
(-3300 1525);
FORCEPROP 3 LASTPIN (-3250 1525) SIG_NAME P5E_CPU1_P2_TX_BUF_DN<3>
J 0
(-3240 1535);
DISPLAY 0.659574 (-3240 1535);
PAINT MONO (-3240 1535);
DISPLAY INVISIBLE (-3240 1535);
FORCEPROP 1 LASTPIN (-3250 1525) BN 3
J 2
(-3238 1533);
DISPLAY 0.680851 (-3238 1533);
PAINT GREEN (-3238 1533);
FORCEPROP 2 LAST CDS_LIB standard
J 0
(-3300 1525);
DISPLAY INVISIBLE (-3300 1525);
FORCEPROP 1 LAST BODY_TYPE PLUMBING
J 2
(-3300 1575);
DISPLAY 0.872340 (-3300 1575);
PAINT GREEN (-3300 1575);
DISPLAY INVISIBLE (-3300 1575);
FORCEPROP 1 LAST HDL_TAP TRUE
J 2
(-3625 1400);
DISPLAY 0.872340 (-3625 1400);
DISPLAY INVISIBLE (-3625 1400);
FORCEPROP 1 LAST PATH I11
J 2
(-3298 1525);
DISPLAY 0.872340 (-3298 1525);
PAINT GREEN (-3298 1525);
DISPLAY INVISIBLE (-3298 1525);
FORCEADD TAP..1
(-6550 1650);
FORCEPROP 3 LASTPIN (-6600 1650) SIG_NAME P5E_CPU1_P2_TX_BUF_C_DP<11>
J 0
(-6590 1660);
DISPLAY 0.659574 (-6590 1660);
PAINT MONO (-6590 1660);
DISPLAY INVISIBLE (-6590 1660);
FORCEPROP 1 LASTPIN (-6600 1650) BN 11
J 0
(-6612 1658);
DISPLAY 0.680851 (-6612 1658);
PAINT GREEN (-6612 1658);
FORCEPROP 2 LAST CDS_LIB standard
J 0
(-6550 1650);
DISPLAY INVISIBLE (-6550 1650);
FORCEPROP 1 LAST BODY_TYPE PLUMBING
J 0
(-6550 1700);
DISPLAY 0.872340 (-6550 1700);
PAINT GREEN (-6550 1700);
DISPLAY INVISIBLE (-6550 1700);
FORCEPROP 1 LAST HDL_TAP TRUE
J 0
(-6225 1525);
DISPLAY 0.872340 (-6225 1525);
DISPLAY INVISIBLE (-6225 1525);
FORCEPROP 1 LAST PATH I110
J 0
(-6552 1650);
DISPLAY 0.872340 (-6552 1650);
PAINT GREEN (-6552 1650);
DISPLAY INVISIBLE (-6552 1650);
FORCEADD TAP..1
(-6550 1850);
FORCEPROP 3 LASTPIN (-6600 1850) SIG_NAME P5E_CPU1_P2_TX_BUF_C_DP<10>
J 0
(-6590 1860);
DISPLAY 0.659574 (-6590 1860);
PAINT MONO (-6590 1860);
DISPLAY INVISIBLE (-6590 1860);
FORCEPROP 1 LASTPIN (-6600 1850) BN 10
J 0
(-6612 1858);
DISPLAY 0.680851 (-6612 1858);
PAINT GREEN (-6612 1858);
FORCEPROP 2 LAST CDS_LIB standard
J 0
(-6550 1850);
DISPLAY INVISIBLE (-6550 1850);
FORCEPROP 1 LAST BODY_TYPE PLUMBING
J 0
(-6550 1900);
DISPLAY 0.872340 (-6550 1900);
PAINT GREEN (-6550 1900);
DISPLAY INVISIBLE (-6550 1900);
FORCEPROP 1 LAST HDL_TAP TRUE
J 0
(-6225 1725);
DISPLAY 0.872340 (-6225 1725);
DISPLAY INVISIBLE (-6225 1725);
FORCEPROP 1 LAST PATH I111
J 0
(-6552 1850);
DISPLAY 0.872340 (-6552 1850);
PAINT GREEN (-6552 1850);
DISPLAY INVISIBLE (-6552 1850);
FORCEADD TAP..1
(-6550 2050);
FORCEPROP 3 LASTPIN (-6600 2050) SIG_NAME P5E_CPU1_P2_TX_BUF_C_DP<9>
J 0
(-6590 2060);
DISPLAY 0.659574 (-6590 2060);
PAINT MONO (-6590 2060);
DISPLAY INVISIBLE (-6590 2060);
FORCEPROP 1 LASTPIN (-6600 2050) BN 9
J 0
(-6612 2058);
DISPLAY 0.680851 (-6612 2058);
PAINT GREEN (-6612 2058);
FORCEPROP 2 LAST CDS_LIB standard
J 0
(-6550 2050);
DISPLAY INVISIBLE (-6550 2050);
FORCEPROP 1 LAST BODY_TYPE PLUMBING
J 0
(-6550 2100);
DISPLAY 0.872340 (-6550 2100);
PAINT GREEN (-6550 2100);
DISPLAY INVISIBLE (-6550 2100);
FORCEPROP 1 LAST HDL_TAP TRUE
J 0
(-6225 1925);
DISPLAY 0.872340 (-6225 1925);
DISPLAY INVISIBLE (-6225 1925);
FORCEPROP 1 LAST PATH I112
J 0
(-6552 2050);
DISPLAY 0.872340 (-6552 2050);
PAINT GREEN (-6552 2050);
DISPLAY INVISIBLE (-6552 2050);
FORCEADD TAP..1
(-6350 1200);
FORCEPROP 3 LASTPIN (-6400 1200) SIG_NAME P5E_CPU1_P2_TX_BUF_C_DN<13>
J 0
(-6390 1210);
DISPLAY 0.659574 (-6390 1210);
PAINT MONO (-6390 1210);
DISPLAY INVISIBLE (-6390 1210);
FORCEPROP 1 LASTPIN (-6400 1200) BN 13
J 0
(-6412 1208);
DISPLAY 0.680851 (-6412 1208);
PAINT GREEN (-6412 1208);
FORCEPROP 2 LAST CDS_LIB standard
J 0
(-6350 1200);
DISPLAY INVISIBLE (-6350 1200);
FORCEPROP 1 LAST BODY_TYPE PLUMBING
J 0
(-6350 1250);
DISPLAY 0.872340 (-6350 1250);
PAINT GREEN (-6350 1250);
DISPLAY INVISIBLE (-6350 1250);
FORCEPROP 1 LAST HDL_TAP TRUE
J 0
(-6025 1075);
DISPLAY 0.872340 (-6025 1075);
DISPLAY INVISIBLE (-6025 1075);
FORCEPROP 1 LAST PATH I113
J 0
(-6352 1200);
DISPLAY 0.872340 (-6352 1200);
PAINT GREEN (-6352 1200);
DISPLAY INVISIBLE (-6352 1200);
FORCEADD TAP..1
(-6350 1400);
FORCEPROP 3 LASTPIN (-6400 1400) SIG_NAME P5E_CPU1_P2_TX_BUF_C_DN<12>
J 0
(-6390 1410);
DISPLAY 0.659574 (-6390 1410);
PAINT MONO (-6390 1410);
DISPLAY INVISIBLE (-6390 1410);
FORCEPROP 1 LASTPIN (-6400 1400) BN 12
J 0
(-6412 1408);
DISPLAY 0.680851 (-6412 1408);
PAINT GREEN (-6412 1408);
FORCEPROP 2 LAST CDS_LIB standard
J 0
(-6350 1400);
DISPLAY INVISIBLE (-6350 1400);
FORCEPROP 1 LAST BODY_TYPE PLUMBING
J 0
(-6350 1450);
DISPLAY 0.872340 (-6350 1450);
PAINT GREEN (-6350 1450);
DISPLAY INVISIBLE (-6350 1450);
FORCEPROP 1 LAST HDL_TAP TRUE
J 0
(-6025 1275);
DISPLAY 0.872340 (-6025 1275);
DISPLAY INVISIBLE (-6025 1275);
FORCEPROP 1 LAST PATH I114
J 0
(-6352 1400);
DISPLAY 0.872340 (-6352 1400);
PAINT GREEN (-6352 1400);
DISPLAY INVISIBLE (-6352 1400);
FORCEADD TAP..1
(-6350 1600);
FORCEPROP 3 LASTPIN (-6400 1600) SIG_NAME P5E_CPU1_P2_TX_BUF_C_DN<11>
J 0
(-6390 1610);
DISPLAY 0.659574 (-6390 1610);
PAINT MONO (-6390 1610);
DISPLAY INVISIBLE (-6390 1610);
FORCEPROP 1 LASTPIN (-6400 1600) BN 11
J 0
(-6412 1608);
DISPLAY 0.680851 (-6412 1608);
PAINT GREEN (-6412 1608);
FORCEPROP 2 LAST CDS_LIB standard
J 0
(-6350 1600);
DISPLAY INVISIBLE (-6350 1600);
FORCEPROP 1 LAST BODY_TYPE PLUMBING
J 0
(-6350 1650);
DISPLAY 0.872340 (-6350 1650);
PAINT GREEN (-6350 1650);
DISPLAY INVISIBLE (-6350 1650);
FORCEPROP 1 LAST HDL_TAP TRUE
J 0
(-6025 1475);
DISPLAY 0.872340 (-6025 1475);
DISPLAY INVISIBLE (-6025 1475);
FORCEPROP 1 LAST PATH I115
J 0
(-6352 1600);
DISPLAY 0.872340 (-6352 1600);
PAINT GREEN (-6352 1600);
DISPLAY INVISIBLE (-6352 1600);
FORCEADD TAP..1
(-6350 1800);
FORCEPROP 3 LASTPIN (-6400 1800) SIG_NAME P5E_CPU1_P2_TX_BUF_C_DN<10>
J 0
(-6390 1810);
DISPLAY 0.659574 (-6390 1810);
PAINT MONO (-6390 1810);
DISPLAY INVISIBLE (-6390 1810);
FORCEPROP 1 LASTPIN (-6400 1800) BN 10
J 0
(-6412 1808);
DISPLAY 0.680851 (-6412 1808);
PAINT GREEN (-6412 1808);
FORCEPROP 2 LAST CDS_LIB standard
J 0
(-6350 1800);
DISPLAY INVISIBLE (-6350 1800);
FORCEPROP 1 LAST BODY_TYPE PLUMBING
J 0
(-6350 1850);
DISPLAY 0.872340 (-6350 1850);
PAINT GREEN (-6350 1850);
DISPLAY INVISIBLE (-6350 1850);
FORCEPROP 1 LAST HDL_TAP TRUE
J 0
(-6025 1675);
DISPLAY 0.872340 (-6025 1675);
DISPLAY INVISIBLE (-6025 1675);
FORCEPROP 1 LAST PATH I116
J 0
(-6352 1800);
DISPLAY 0.872340 (-6352 1800);
PAINT GREEN (-6352 1800);
DISPLAY INVISIBLE (-6352 1800);
FORCEADD TAP..1
(-6350 2000);
FORCEPROP 3 LASTPIN (-6400 2000) SIG_NAME P5E_CPU1_P2_TX_BUF_C_DN<9>
J 0
(-6390 2010);
DISPLAY 0.659574 (-6390 2010);
PAINT MONO (-6390 2010);
DISPLAY INVISIBLE (-6390 2010);
FORCEPROP 1 LASTPIN (-6400 2000) BN 9
J 0
(-6412 2008);
DISPLAY 0.680851 (-6412 2008);
PAINT GREEN (-6412 2008);
FORCEPROP 2 LAST CDS_LIB standard
J 0
(-6350 2000);
DISPLAY INVISIBLE (-6350 2000);
FORCEPROP 1 LAST BODY_TYPE PLUMBING
J 0
(-6350 2050);
DISPLAY 0.872340 (-6350 2050);
PAINT GREEN (-6350 2050);
DISPLAY INVISIBLE (-6350 2050);
FORCEPROP 1 LAST HDL_TAP TRUE
J 0
(-6025 1875);
DISPLAY 0.872340 (-6025 1875);
DISPLAY INVISIBLE (-6025 1875);
FORCEPROP 1 LAST PATH I117
J 0
(-6352 2000);
DISPLAY 0.872340 (-6352 2000);
PAINT GREEN (-6352 2000);
DISPLAY INVISIBLE (-6352 2000);
FORCEADD TAP..1
(-6550 2250);
FORCEPROP 3 LASTPIN (-6600 2250) SIG_NAME P5E_CPU1_P2_TX_BUF_C_DP<8>
J 0
(-6590 2260);
DISPLAY 0.659574 (-6590 2260);
PAINT MONO (-6590 2260);
DISPLAY INVISIBLE (-6590 2260);
FORCEPROP 1 LASTPIN (-6600 2250) BN 8
J 0
(-6612 2258);
DISPLAY 0.680851 (-6612 2258);
PAINT GREEN (-6612 2258);
FORCEPROP 2 LAST CDS_LIB standard
J 0
(-6550 2250);
DISPLAY INVISIBLE (-6550 2250);
FORCEPROP 1 LAST BODY_TYPE PLUMBING
J 0
(-6550 2300);
DISPLAY 0.872340 (-6550 2300);
PAINT GREEN (-6550 2300);
DISPLAY INVISIBLE (-6550 2300);
FORCEPROP 1 LAST HDL_TAP TRUE
J 0
(-6225 2125);
DISPLAY 0.872340 (-6225 2125);
DISPLAY INVISIBLE (-6225 2125);
FORCEPROP 1 LAST PATH I118
J 0
(-6552 2250);
DISPLAY 0.872340 (-6552 2250);
PAINT GREEN (-6552 2250);
DISPLAY INVISIBLE (-6552 2250);
FORCEADD TAP..1
(-6350 2200);
FORCEPROP 3 LASTPIN (-6400 2200) SIG_NAME P5E_CPU1_P2_TX_BUF_C_DN<8>
J 0
(-6390 2210);
DISPLAY 0.659574 (-6390 2210);
PAINT MONO (-6390 2210);
DISPLAY INVISIBLE (-6390 2210);
FORCEPROP 1 LASTPIN (-6400 2200) BN 8
J 0
(-6412 2208);
DISPLAY 0.680851 (-6412 2208);
PAINT GREEN (-6412 2208);
FORCEPROP 2 LAST CDS_LIB standard
J 0
(-6350 2200);
DISPLAY INVISIBLE (-6350 2200);
FORCEPROP 1 LAST BODY_TYPE PLUMBING
J 0
(-6350 2250);
DISPLAY 0.872340 (-6350 2250);
PAINT GREEN (-6350 2250);
DISPLAY INVISIBLE (-6350 2250);
FORCEPROP 1 LAST HDL_TAP TRUE
J 0
(-6025 2075);
DISPLAY 0.872340 (-6025 2075);
DISPLAY INVISIBLE (-6025 2075);
FORCEPROP 1 LAST PATH I119
J 0
(-6352 2200);
DISPLAY 0.872340 (-6352 2200);
PAINT GREEN (-6352 2200);
DISPLAY INVISIBLE (-6352 2200);
FORCEADD TAP..1
R 2
(-3300 1725);
FORCEPROP 3 LASTPIN (-3250 1725) SIG_NAME P5E_CPU1_P2_TX_BUF_DN<2>
J 0
(-3240 1735);
DISPLAY 0.659574 (-3240 1735);
PAINT MONO (-3240 1735);
DISPLAY INVISIBLE (-3240 1735);
FORCEPROP 1 LASTPIN (-3250 1725) BN 2
J 2
(-3238 1733);
DISPLAY 0.680851 (-3238 1733);
PAINT GREEN (-3238 1733);
FORCEPROP 2 LAST CDS_LIB standard
J 0
(-3300 1725);
DISPLAY INVISIBLE (-3300 1725);
FORCEPROP 1 LAST BODY_TYPE PLUMBING
J 2
(-3300 1775);
DISPLAY 0.872340 (-3300 1775);
PAINT GREEN (-3300 1775);
DISPLAY INVISIBLE (-3300 1775);
FORCEPROP 1 LAST HDL_TAP TRUE
J 2
(-3625 1600);
DISPLAY 0.872340 (-3625 1600);
DISPLAY INVISIBLE (-3625 1600);
FORCEPROP 1 LAST PATH I12
J 2
(-3298 1725);
DISPLAY 0.872340 (-3298 1725);
PAINT GREEN (-3298 1725);
DISPLAY INVISIBLE (-3298 1725);
FORCEADD TAP..1
(-1875 3400);
FORCEPROP 3 LASTPIN (-1925 3400) SIG_NAME P5E_CPU1_P2_TX_BUF_DP<0>
J 0
(-1915 3410);
DISPLAY 0.659574 (-1915 3410);
PAINT MONO (-1915 3410);
DISPLAY INVISIBLE (-1915 3410);
FORCEPROP 1 LASTPIN (-1925 3400) BN 0
J 0
(-1937 3408);
DISPLAY 0.680851 (-1937 3408);
PAINT GREEN (-1937 3408);
FORCEPROP 2 LAST CDS_LIB standard
J 0
(-1875 3400);
DISPLAY INVISIBLE (-1875 3400);
FORCEPROP 1 LAST BODY_TYPE PLUMBING
J 0
(-1875 3450);
DISPLAY 0.872340 (-1875 3450);
PAINT GREEN (-1875 3450);
DISPLAY INVISIBLE (-1875 3450);
FORCEPROP 1 LAST HDL_TAP TRUE
J 0
(-1550 3275);
DISPLAY 0.872340 (-1550 3275);
DISPLAY INVISIBLE (-1550 3275);
FORCEPROP 1 LAST PATH I120
J 0
(-1877 3400);
DISPLAY 0.872340 (-1877 3400);
PAINT GREEN (-1877 3400);
DISPLAY INVISIBLE (-1877 3400);
FORCEADD TAP..1
(-1875 3750);
FORCEPROP 3 LASTPIN (-1925 3750) SIG_NAME P5E_CPU1_P2_TX_BUF_DP<1>
J 0
(-1915 3760);
DISPLAY 0.659574 (-1915 3760);
PAINT MONO (-1915 3760);
DISPLAY INVISIBLE (-1915 3760);
FORCEPROP 1 LASTPIN (-1925 3750) BN 1
J 0
(-1937 3758);
DISPLAY 0.680851 (-1937 3758);
PAINT GREEN (-1937 3758);
FORCEPROP 2 LAST CDS_LIB standard
J 0
(-1875 3750);
DISPLAY INVISIBLE (-1875 3750);
FORCEPROP 1 LAST BODY_TYPE PLUMBING
J 0
(-1875 3800);
DISPLAY 0.872340 (-1875 3800);
PAINT GREEN (-1875 3800);
DISPLAY INVISIBLE (-1875 3800);
FORCEPROP 1 LAST HDL_TAP TRUE
J 0
(-1550 3625);
DISPLAY 0.872340 (-1550 3625);
DISPLAY INVISIBLE (-1550 3625);
FORCEPROP 1 LAST PATH I121
J 0
(-1877 3750);
DISPLAY 0.872340 (-1877 3750);
PAINT GREEN (-1877 3750);
DISPLAY INVISIBLE (-1877 3750);
FORCEADD TAP..1
(-1875 4100);
FORCEPROP 3 LASTPIN (-1925 4100) SIG_NAME P5E_CPU1_P2_TX_BUF_DP<2>
J 0
(-1915 4110);
DISPLAY 0.659574 (-1915 4110);
PAINT MONO (-1915 4110);
DISPLAY INVISIBLE (-1915 4110);
FORCEPROP 1 LASTPIN (-1925 4100) BN 2
J 0
(-1937 4108);
DISPLAY 0.680851 (-1937 4108);
PAINT GREEN (-1937 4108);
FORCEPROP 2 LAST CDS_LIB standard
J 0
(-1875 4100);
DISPLAY INVISIBLE (-1875 4100);
FORCEPROP 1 LAST BODY_TYPE PLUMBING
J 0
(-1875 4150);
DISPLAY 0.872340 (-1875 4150);
PAINT GREEN (-1875 4150);
DISPLAY INVISIBLE (-1875 4150);
FORCEPROP 1 LAST HDL_TAP TRUE
J 0
(-1550 3975);
DISPLAY 0.872340 (-1550 3975);
DISPLAY INVISIBLE (-1550 3975);
FORCEPROP 1 LAST PATH I122
J 0
(-1877 4100);
DISPLAY 0.872340 (-1877 4100);
PAINT GREEN (-1877 4100);
DISPLAY INVISIBLE (-1877 4100);
FORCEADD TAP..1
(-1675 3300);
FORCEPROP 3 LASTPIN (-1725 3300) SIG_NAME P5E_CPU1_P2_TX_BUF_DN<0>
J 0
(-1715 3310);
DISPLAY 0.659574 (-1715 3310);
PAINT MONO (-1715 3310);
DISPLAY INVISIBLE (-1715 3310);
FORCEPROP 1 LASTPIN (-1725 3300) BN 0
J 0
(-1737 3308);
DISPLAY 0.680851 (-1737 3308);
PAINT GREEN (-1737 3308);
FORCEPROP 2 LAST CDS_LIB standard
J 0
(-1675 3300);
DISPLAY INVISIBLE (-1675 3300);
FORCEPROP 1 LAST BODY_TYPE PLUMBING
J 0
(-1675 3350);
DISPLAY 0.872340 (-1675 3350);
PAINT GREEN (-1675 3350);
DISPLAY INVISIBLE (-1675 3350);
FORCEPROP 1 LAST HDL_TAP TRUE
J 0
(-1350 3175);
DISPLAY 0.872340 (-1350 3175);
DISPLAY INVISIBLE (-1350 3175);
FORCEPROP 1 LAST PATH I123
J 0
(-1677 3300);
DISPLAY 0.872340 (-1677 3300);
PAINT GREEN (-1677 3300);
DISPLAY INVISIBLE (-1677 3300);
FORCEADD TAP..1
(-1675 3650);
FORCEPROP 3 LASTPIN (-1725 3650) SIG_NAME P5E_CPU1_P2_TX_BUF_DN<1>
J 0
(-1715 3660);
DISPLAY 0.659574 (-1715 3660);
PAINT MONO (-1715 3660);
DISPLAY INVISIBLE (-1715 3660);
FORCEPROP 1 LASTPIN (-1725 3650) BN 1
J 0
(-1737 3658);
DISPLAY 0.680851 (-1737 3658);
PAINT GREEN (-1737 3658);
FORCEPROP 2 LAST CDS_LIB standard
J 0
(-1675 3650);
DISPLAY INVISIBLE (-1675 3650);
FORCEPROP 1 LAST BODY_TYPE PLUMBING
J 0
(-1675 3700);
DISPLAY 0.872340 (-1675 3700);
PAINT GREEN (-1675 3700);
DISPLAY INVISIBLE (-1675 3700);
FORCEPROP 1 LAST HDL_TAP TRUE
J 0
(-1350 3525);
DISPLAY 0.872340 (-1350 3525);
DISPLAY INVISIBLE (-1350 3525);
FORCEPROP 1 LAST PATH I124
J 0
(-1677 3650);
DISPLAY 0.872340 (-1677 3650);
PAINT GREEN (-1677 3650);
DISPLAY INVISIBLE (-1677 3650);
FORCEADD TAP..1
(-1675 4000);
FORCEPROP 3 LASTPIN (-1725 4000) SIG_NAME P5E_CPU1_P2_TX_BUF_DN<2>
J 0
(-1715 4010);
DISPLAY 0.659574 (-1715 4010);
PAINT MONO (-1715 4010);
DISPLAY INVISIBLE (-1715 4010);
FORCEPROP 1 LASTPIN (-1725 4000) BN 2
J 0
(-1737 4008);
DISPLAY 0.680851 (-1737 4008);
PAINT GREEN (-1737 4008);
FORCEPROP 2 LAST CDS_LIB standard
J 0
(-1675 4000);
DISPLAY INVISIBLE (-1675 4000);
FORCEPROP 1 LAST BODY_TYPE PLUMBING
J 0
(-1675 4050);
DISPLAY 0.872340 (-1675 4050);
PAINT GREEN (-1675 4050);
DISPLAY INVISIBLE (-1675 4050);
FORCEPROP 1 LAST HDL_TAP TRUE
J 0
(-1350 3875);
DISPLAY 0.872340 (-1350 3875);
DISPLAY INVISIBLE (-1350 3875);
FORCEPROP 1 LAST PATH I125
J 0
(-1677 4000);
DISPLAY 0.872340 (-1677 4000);
PAINT GREEN (-1677 4000);
DISPLAY INVISIBLE (-1677 4000);
FORCEADD OFFPAGE..2
(-5350 2275);
FORCEPROP 2 LAST $XR0 119 
J 0
(-5161 2275);
DISPLAY 0.638298 (-5161 2275);
PAINT MONO (-5161 2275);
FORCEPROP 2 LAST CDS_LIB standard
J 0
(-5350 2275);
DISPLAY INVISIBLE (-5350 2275);
FORCEPROP 1 LAST OFFPAGE TRUE
J 0
(-5025 2150);
DISPLAY 0.872340 (-5025 2150);
DISPLAY INVISIBLE (-5025 2150);
FORCEPROP 1 LAST COMMENT_BODY TRUE
J 0
(-5395 2180);
DISPLAY 0.872340 (-5395 2180);
PAINT GREEN (-5395 2180);
DISPLAY INVISIBLE (-5395 2180);
FORCEPROP 2 LAST PATH I126
J 0
(-5150 2325);
DISPLAY 0.680851 (-5150 2325);
DISPLAY INVISIBLE (-5150 2325);
FORCEADD OFFPAGE..2
(-5350 2225);
FORCEPROP 2 LAST $XR0 119 
J 0
(-5161 2225);
DISPLAY 0.638298 (-5161 2225);
PAINT MONO (-5161 2225);
FORCEPROP 2 LAST CDS_LIB standard
J 0
(-5350 2225);
DISPLAY INVISIBLE (-5350 2225);
FORCEPROP 1 LAST OFFPAGE TRUE
J 0
(-5025 2100);
DISPLAY 0.872340 (-5025 2100);
DISPLAY INVISIBLE (-5025 2100);
FORCEPROP 1 LAST COMMENT_BODY TRUE
J 0
(-5395 2130);
DISPLAY 0.872340 (-5395 2130);
PAINT GREEN (-5395 2130);
DISPLAY INVISIBLE (-5395 2130);
FORCEPROP 2 LAST PATH I127
J 0
(-5150 2275);
DISPLAY 0.680851 (-5150 2275);
DISPLAY INVISIBLE (-5150 2275);
FORCEADD TAP..1
(-1875 4450);
FORCEPROP 3 LASTPIN (-1925 4450) SIG_NAME P5E_CPU1_P2_TX_BUF_DP<3>
J 0
(-1915 4460);
DISPLAY 0.659574 (-1915 4460);
PAINT MONO (-1915 4460);
DISPLAY INVISIBLE (-1915 4460);
FORCEPROP 1 LASTPIN (-1925 4450) BN 3
J 0
(-1937 4458);
DISPLAY 0.680851 (-1937 4458);
PAINT GREEN (-1937 4458);
FORCEPROP 2 LAST CDS_LIB standard
J 0
(-1875 4450);
DISPLAY INVISIBLE (-1875 4450);
FORCEPROP 1 LAST BODY_TYPE PLUMBING
J 0
(-1875 4500);
DISPLAY 0.872340 (-1875 4500);
PAINT GREEN (-1875 4500);
DISPLAY INVISIBLE (-1875 4500);
FORCEPROP 1 LAST HDL_TAP TRUE
J 0
(-1550 4325);
DISPLAY 0.872340 (-1550 4325);
DISPLAY INVISIBLE (-1550 4325);
FORCEPROP 1 LAST PATH I128
J 0
(-1877 4450);
DISPLAY 0.872340 (-1877 4450);
PAINT GREEN (-1877 4450);
DISPLAY INVISIBLE (-1877 4450);
FORCEADD TAP..1
(-1875 4800);
FORCEPROP 3 LASTPIN (-1925 4800) SIG_NAME P5E_CPU1_P2_TX_BUF_DP<4>
J 0
(-1915 4810);
DISPLAY 0.659574 (-1915 4810);
PAINT MONO (-1915 4810);
DISPLAY INVISIBLE (-1915 4810);
FORCEPROP 1 LASTPIN (-1925 4800) BN 4
J 0
(-1937 4808);
DISPLAY 0.680851 (-1937 4808);
PAINT GREEN (-1937 4808);
FORCEPROP 2 LAST CDS_LIB standard
J 0
(-1875 4800);
DISPLAY INVISIBLE (-1875 4800);
FORCEPROP 1 LAST BODY_TYPE PLUMBING
J 0
(-1875 4850);
DISPLAY 0.872340 (-1875 4850);
PAINT GREEN (-1875 4850);
DISPLAY INVISIBLE (-1875 4850);
FORCEPROP 1 LAST HDL_TAP TRUE
J 0
(-1550 4675);
DISPLAY 0.872340 (-1550 4675);
DISPLAY INVISIBLE (-1550 4675);
FORCEPROP 1 LAST PATH I129
J 0
(-1877 4800);
DISPLAY 0.872340 (-1877 4800);
PAINT GREEN (-1877 4800);
DISPLAY INVISIBLE (-1877 4800);
FORCEADD TAP..1
R 2
(-3300 1925);
FORCEPROP 3 LASTPIN (-3250 1925) SIG_NAME P5E_CPU1_P2_TX_BUF_DN<1>
J 0
(-3240 1935);
DISPLAY 0.659574 (-3240 1935);
PAINT MONO (-3240 1935);
DISPLAY INVISIBLE (-3240 1935);
FORCEPROP 1 LASTPIN (-3250 1925) BN 1
J 2
(-3238 1933);
DISPLAY 0.680851 (-3238 1933);
PAINT GREEN (-3238 1933);
FORCEPROP 2 LAST CDS_LIB standard
J 0
(-3300 1925);
DISPLAY INVISIBLE (-3300 1925);
FORCEPROP 1 LAST BODY_TYPE PLUMBING
J 2
(-3300 1975);
DISPLAY 0.872340 (-3300 1975);
PAINT GREEN (-3300 1975);
DISPLAY INVISIBLE (-3300 1975);
FORCEPROP 1 LAST HDL_TAP TRUE
J 2
(-3625 1800);
DISPLAY 0.872340 (-3625 1800);
DISPLAY INVISIBLE (-3625 1800);
FORCEPROP 1 LAST PATH I13
J 2
(-3298 1925);
DISPLAY 0.872340 (-3298 1925);
PAINT GREEN (-3298 1925);
DISPLAY INVISIBLE (-3298 1925);
FORCEADD TAP..1
(-1875 5150);
FORCEPROP 3 LASTPIN (-1925 5150) SIG_NAME P5E_CPU1_P2_TX_BUF_DP<5>
J 0
(-1915 5160);
DISPLAY 0.659574 (-1915 5160);
PAINT MONO (-1915 5160);
DISPLAY INVISIBLE (-1915 5160);
FORCEPROP 1 LASTPIN (-1925 5150) BN 5
J 0
(-1937 5158);
DISPLAY 0.680851 (-1937 5158);
PAINT GREEN (-1937 5158);
FORCEPROP 2 LAST CDS_LIB standard
J 0
(-1875 5150);
DISPLAY INVISIBLE (-1875 5150);
FORCEPROP 1 LAST BODY_TYPE PLUMBING
J 0
(-1875 5200);
DISPLAY 0.872340 (-1875 5200);
PAINT GREEN (-1875 5200);
DISPLAY INVISIBLE (-1875 5200);
FORCEPROP 1 LAST HDL_TAP TRUE
J 0
(-1550 5025);
DISPLAY 0.872340 (-1550 5025);
DISPLAY INVISIBLE (-1550 5025);
FORCEPROP 1 LAST PATH I130
J 0
(-1877 5150);
DISPLAY 0.872340 (-1877 5150);
PAINT GREEN (-1877 5150);
DISPLAY INVISIBLE (-1877 5150);
FORCEADD TAP..1
(-1675 4350);
FORCEPROP 3 LASTPIN (-1725 4350) SIG_NAME P5E_CPU1_P2_TX_BUF_DN<3>
J 0
(-1715 4360);
DISPLAY 0.659574 (-1715 4360);
PAINT MONO (-1715 4360);
DISPLAY INVISIBLE (-1715 4360);
FORCEPROP 1 LASTPIN (-1725 4350) BN 3
J 0
(-1737 4358);
DISPLAY 0.680851 (-1737 4358);
PAINT GREEN (-1737 4358);
FORCEPROP 2 LAST CDS_LIB standard
J 0
(-1675 4350);
DISPLAY INVISIBLE (-1675 4350);
FORCEPROP 1 LAST BODY_TYPE PLUMBING
J 0
(-1675 4400);
DISPLAY 0.872340 (-1675 4400);
PAINT GREEN (-1675 4400);
DISPLAY INVISIBLE (-1675 4400);
FORCEPROP 1 LAST HDL_TAP TRUE
J 0
(-1350 4225);
DISPLAY 0.872340 (-1350 4225);
DISPLAY INVISIBLE (-1350 4225);
FORCEPROP 1 LAST PATH I131
J 0
(-1677 4350);
DISPLAY 0.872340 (-1677 4350);
PAINT GREEN (-1677 4350);
DISPLAY INVISIBLE (-1677 4350);
FORCEADD TAP..1
(-1675 4700);
FORCEPROP 3 LASTPIN (-1725 4700) SIG_NAME P5E_CPU1_P2_TX_BUF_DN<4>
J 0
(-1715 4710);
DISPLAY 0.659574 (-1715 4710);
PAINT MONO (-1715 4710);
DISPLAY INVISIBLE (-1715 4710);
FORCEPROP 1 LASTPIN (-1725 4700) BN 4
J 0
(-1737 4708);
DISPLAY 0.680851 (-1737 4708);
PAINT GREEN (-1737 4708);
FORCEPROP 2 LAST CDS_LIB standard
J 0
(-1675 4700);
DISPLAY INVISIBLE (-1675 4700);
FORCEPROP 1 LAST BODY_TYPE PLUMBING
J 0
(-1675 4750);
DISPLAY 0.872340 (-1675 4750);
PAINT GREEN (-1675 4750);
DISPLAY INVISIBLE (-1675 4750);
FORCEPROP 1 LAST HDL_TAP TRUE
J 0
(-1350 4575);
DISPLAY 0.872340 (-1350 4575);
DISPLAY INVISIBLE (-1350 4575);
FORCEPROP 1 LAST PATH I132
J 0
(-1677 4700);
DISPLAY 0.872340 (-1677 4700);
PAINT GREEN (-1677 4700);
DISPLAY INVISIBLE (-1677 4700);
FORCEADD TAP..1
(-1675 5050);
FORCEPROP 3 LASTPIN (-1725 5050) SIG_NAME P5E_CPU1_P2_TX_BUF_DN<5>
J 0
(-1715 5060);
DISPLAY 0.659574 (-1715 5060);
PAINT MONO (-1715 5060);
DISPLAY INVISIBLE (-1715 5060);
FORCEPROP 1 LASTPIN (-1725 5050) BN 5
J 0
(-1737 5058);
DISPLAY 0.680851 (-1737 5058);
PAINT GREEN (-1737 5058);
FORCEPROP 2 LAST CDS_LIB standard
J 0
(-1675 5050);
DISPLAY INVISIBLE (-1675 5050);
FORCEPROP 1 LAST BODY_TYPE PLUMBING
J 0
(-1675 5100);
DISPLAY 0.872340 (-1675 5100);
PAINT GREEN (-1675 5100);
DISPLAY INVISIBLE (-1675 5100);
FORCEPROP 1 LAST HDL_TAP TRUE
J 0
(-1350 4925);
DISPLAY 0.872340 (-1350 4925);
DISPLAY INVISIBLE (-1350 4925);
FORCEPROP 1 LAST PATH I133
J 0
(-1677 5050);
DISPLAY 0.872340 (-1677 5050);
PAINT GREEN (-1677 5050);
DISPLAY INVISIBLE (-1677 5050);
FORCEADD TAP..1
(-1875 5500);
FORCEPROP 3 LASTPIN (-1925 5500) SIG_NAME P5E_CPU1_P2_TX_BUF_DP<6>
J 0
(-1915 5510);
DISPLAY 0.659574 (-1915 5510);
PAINT MONO (-1915 5510);
DISPLAY INVISIBLE (-1915 5510);
FORCEPROP 1 LASTPIN (-1925 5500) BN 6
J 0
(-1937 5508);
DISPLAY 0.680851 (-1937 5508);
PAINT GREEN (-1937 5508);
FORCEPROP 2 LAST CDS_LIB standard
J 0
(-1875 5500);
DISPLAY INVISIBLE (-1875 5500);
FORCEPROP 1 LAST BODY_TYPE PLUMBING
J 0
(-1875 5550);
DISPLAY 0.872340 (-1875 5550);
PAINT GREEN (-1875 5550);
DISPLAY INVISIBLE (-1875 5550);
FORCEPROP 1 LAST HDL_TAP TRUE
J 0
(-1550 5375);
DISPLAY 0.872340 (-1550 5375);
DISPLAY INVISIBLE (-1550 5375);
FORCEPROP 1 LAST PATH I134
J 0
(-1877 5500);
DISPLAY 0.872340 (-1877 5500);
PAINT GREEN (-1877 5500);
DISPLAY INVISIBLE (-1877 5500);
FORCEADD TAP..1
(-1875 5850);
FORCEPROP 3 LASTPIN (-1925 5850) SIG_NAME P5E_CPU1_P2_TX_BUF_DP<7>
J 0
(-1915 5860);
DISPLAY 0.659574 (-1915 5860);
PAINT MONO (-1915 5860);
DISPLAY INVISIBLE (-1915 5860);
FORCEPROP 1 LASTPIN (-1925 5850) BN 7
J 0
(-1937 5858);
DISPLAY 0.680851 (-1937 5858);
PAINT GREEN (-1937 5858);
FORCEPROP 2 LAST CDS_LIB standard
J 0
(-1875 5850);
DISPLAY INVISIBLE (-1875 5850);
FORCEPROP 1 LAST BODY_TYPE PLUMBING
J 0
(-1875 5900);
DISPLAY 0.872340 (-1875 5900);
PAINT GREEN (-1875 5900);
DISPLAY INVISIBLE (-1875 5900);
FORCEPROP 1 LAST HDL_TAP TRUE
J 0
(-1550 5725);
DISPLAY 0.872340 (-1550 5725);
DISPLAY INVISIBLE (-1550 5725);
FORCEPROP 1 LAST PATH I135
J 0
(-1877 5850);
DISPLAY 0.872340 (-1877 5850);
PAINT GREEN (-1877 5850);
DISPLAY INVISIBLE (-1877 5850);
FORCEADD TAP..1
(-1675 5400);
FORCEPROP 3 LASTPIN (-1725 5400) SIG_NAME P5E_CPU1_P2_TX_BUF_DN<6>
J 0
(-1715 5410);
DISPLAY 0.659574 (-1715 5410);
PAINT MONO (-1715 5410);
DISPLAY INVISIBLE (-1715 5410);
FORCEPROP 1 LASTPIN (-1725 5400) BN 6
J 0
(-1737 5408);
DISPLAY 0.680851 (-1737 5408);
PAINT GREEN (-1737 5408);
FORCEPROP 2 LAST CDS_LIB standard
J 0
(-1675 5400);
DISPLAY INVISIBLE (-1675 5400);
FORCEPROP 1 LAST BODY_TYPE PLUMBING
J 0
(-1675 5450);
DISPLAY 0.872340 (-1675 5450);
PAINT GREEN (-1675 5450);
DISPLAY INVISIBLE (-1675 5450);
FORCEPROP 1 LAST HDL_TAP TRUE
J 0
(-1350 5275);
DISPLAY 0.872340 (-1350 5275);
DISPLAY INVISIBLE (-1350 5275);
FORCEPROP 1 LAST PATH I136
J 0
(-1677 5400);
DISPLAY 0.872340 (-1677 5400);
PAINT GREEN (-1677 5400);
DISPLAY INVISIBLE (-1677 5400);
FORCEADD TAP..1
(-1675 5750);
FORCEPROP 3 LASTPIN (-1725 5750) SIG_NAME P5E_CPU1_P2_TX_BUF_DN<7>
J 0
(-1715 5760);
DISPLAY 0.659574 (-1715 5760);
PAINT MONO (-1715 5760);
DISPLAY INVISIBLE (-1715 5760);
FORCEPROP 1 LASTPIN (-1725 5750) BN 7
J 0
(-1737 5758);
DISPLAY 0.680851 (-1737 5758);
PAINT GREEN (-1737 5758);
FORCEPROP 2 LAST CDS_LIB standard
J 0
(-1675 5750);
DISPLAY INVISIBLE (-1675 5750);
FORCEPROP 1 LAST BODY_TYPE PLUMBING
J 0
(-1675 5800);
DISPLAY 0.872340 (-1675 5800);
PAINT GREEN (-1675 5800);
DISPLAY INVISIBLE (-1675 5800);
FORCEPROP 1 LAST HDL_TAP TRUE
J 0
(-1350 5625);
DISPLAY 0.872340 (-1350 5625);
DISPLAY INVISIBLE (-1350 5625);
FORCEPROP 1 LAST PATH I137
J 0
(-1677 5750);
DISPLAY 0.872340 (-1677 5750);
PAINT GREEN (-1677 5750);
DISPLAY INVISIBLE (-1677 5750);
FORCEADD OFFPAGE..5
R 2
(-700 5775);
FORCEPROP 2 LAST $XR0 342 
J 0
(-511 5775);
DISPLAY 0.638298 (-511 5775);
PAINT MONO (-511 5775);
FORCEPROP 2 LAST CDS_LIB standard
J 0
(-700 5775);
DISPLAY INVISIBLE (-700 5775);
FORCEPROP 1 LAST OFFPAGE TRUE
J 2
(-1025 5650);
DISPLAY 0.872340 (-1025 5650);
PAINT GREEN (-1025 5650);
DISPLAY INVISIBLE (-1025 5650);
FORCEPROP 1 LAST COMMENT_BODY TRUE
J 2
(-800 5700);
DISPLAY 0.872340 (-800 5700);
PAINT GREEN (-800 5700);
DISPLAY INVISIBLE (-800 5700);
FORCEPROP 2 LAST PATH I138
J 0
(-525 5850);
DISPLAY 0.680851 (-525 5850);
DISPLAY INVISIBLE (-525 5850);
FORCEADD OFFPAGE..5
R 2
(-675 5875);
FORCEPROP 2 LAST $XR0 342 
J 0
(-486 5875);
DISPLAY 0.638298 (-486 5875);
PAINT MONO (-486 5875);
FORCEPROP 2 LAST CDS_LIB standard
J 0
(-675 5875);
DISPLAY INVISIBLE (-675 5875);
FORCEPROP 1 LAST OFFPAGE TRUE
J 2
(-1000 5750);
DISPLAY 0.872340 (-1000 5750);
PAINT GREEN (-1000 5750);
DISPLAY INVISIBLE (-1000 5750);
FORCEPROP 1 LAST COMMENT_BODY TRUE
J 2
(-775 5800);
DISPLAY 0.872340 (-775 5800);
PAINT GREEN (-775 5800);
DISPLAY INVISIBLE (-775 5800);
FORCEPROP 2 LAST PATH I139
J 0
(-500 5950);
DISPLAY 0.680851 (-500 5950);
DISPLAY INVISIBLE (-500 5950);
FORCEADD TAP..1
R 2
(-3050 1575);
FORCEPROP 3 LASTPIN (-3000 1575) SIG_NAME P5E_CPU1_P2_TX_BUF_DP<3>
J 0
(-2990 1585);
DISPLAY 0.659574 (-2990 1585);
PAINT MONO (-2990 1585);
DISPLAY INVISIBLE (-2990 1585);
FORCEPROP 1 LASTPIN (-3000 1575) BN 3
J 2
(-2988 1583);
DISPLAY 0.680851 (-2988 1583);
PAINT GREEN (-2988 1583);
FORCEPROP 2 LAST CDS_LIB standard
J 0
(-3050 1575);
DISPLAY INVISIBLE (-3050 1575);
FORCEPROP 1 LAST BODY_TYPE PLUMBING
J 2
(-3050 1625);
DISPLAY 0.872340 (-3050 1625);
PAINT GREEN (-3050 1625);
DISPLAY INVISIBLE (-3050 1625);
FORCEPROP 1 LAST HDL_TAP TRUE
J 2
(-3375 1450);
DISPLAY 0.872340 (-3375 1450);
DISPLAY INVISIBLE (-3375 1450);
FORCEPROP 1 LAST PATH I14
J 2
(-3048 1575);
DISPLAY 0.872340 (-3048 1575);
PAINT GREEN (-3048 1575);
DISPLAY INVISIBLE (-3048 1575);
FORCEADD TAP..1
R 2
(-7825 1050);
FORCEPROP 3 LASTPIN (-7775 1050) SIG_NAME P5E_CPU1_P2_TX_BUF_DP<14>
J 0
(-7765 1060);
DISPLAY 0.659574 (-7765 1060);
PAINT MONO (-7765 1060);
DISPLAY INVISIBLE (-7765 1060);
FORCEPROP 1 LASTPIN (-7775 1050) BN 14
J 2
(-7763 1058);
DISPLAY 0.680851 (-7763 1058);
PAINT GREEN (-7763 1058);
FORCEPROP 2 LAST CDS_LIB standard
J 0
(-7825 1050);
DISPLAY INVISIBLE (-7825 1050);
FORCEPROP 1 LAST BODY_TYPE PLUMBING
J 2
(-7825 1100);
DISPLAY 0.872340 (-7825 1100);
PAINT GREEN (-7825 1100);
DISPLAY INVISIBLE (-7825 1100);
FORCEPROP 1 LAST HDL_TAP TRUE
J 2
(-8150 925);
DISPLAY 0.872340 (-8150 925);
DISPLAY INVISIBLE (-8150 925);
FORCEPROP 1 LAST PATH I140
J 2
(-7823 1050);
DISPLAY 0.872340 (-7823 1050);
PAINT GREEN (-7823 1050);
DISPLAY INVISIBLE (-7823 1050);
FORCEADD TAP..1
R 2
(-8075 2000);
FORCEPROP 3 LASTPIN (-8025 2000) SIG_NAME P5E_CPU1_P2_TX_BUF_DN<9>
J 0
(-8015 2010);
DISPLAY 0.659574 (-8015 2010);
PAINT MONO (-8015 2010);
DISPLAY INVISIBLE (-8015 2010);
FORCEPROP 1 LASTPIN (-8025 2000) BN 9
J 2
(-8013 2008);
DISPLAY 0.680851 (-8013 2008);
PAINT GREEN (-8013 2008);
FORCEPROP 2 LAST CDS_LIB standard
J 0
(-8075 2000);
DISPLAY INVISIBLE (-8075 2000);
FORCEPROP 1 LAST BODY_TYPE PLUMBING
J 2
(-8075 2050);
DISPLAY 0.872340 (-8075 2050);
PAINT GREEN (-8075 2050);
DISPLAY INVISIBLE (-8075 2050);
FORCEPROP 1 LAST HDL_TAP TRUE
J 2
(-8400 1875);
DISPLAY 0.872340 (-8400 1875);
DISPLAY INVISIBLE (-8400 1875);
FORCEPROP 1 LAST PATH I141
J 2
(-8073 2000);
DISPLAY 0.872340 (-8073 2000);
PAINT GREEN (-8073 2000);
DISPLAY INVISIBLE (-8073 2000);
FORCEADD PT5161LRS..11
(-2600 4600);
FORCEPROP 1 LAST LOCATION U6016
J 0
(-2950 6225);
DISPLAY 0.723404 (-2950 6225);
PAINT GREEN (-2950 6225);
FORCEPROP 0 LAST $SEC 11
J 0
(-2950 6375);
DISPLAY 0.680851 (-2950 6375);
PAINT MONO (-2950 6375);
DISPLAY INVISIBLE (-2950 6375);
FORCEPROP 0 LAST CDS_SEC 11
J 0
(-2950 6375);
DISPLAY 0.680851 (-2950 6375);
DISPLAY INVISIBLE (-2950 6375);
FORCEPROP 0 LASTPIN (-2150 5750) $PN CK10
J 0
(-2140 5760);
DISPLAY 0.680851 (-2140 5760);
PAINT MONO (-2140 5760);
FORCEPROP 0 LASTPIN (-2150 5400) $PN CU10
J 0
(-2140 5410);
DISPLAY 0.680851 (-2140 5410);
PAINT MONO (-2140 5410);
FORCEPROP 0 LASTPIN (-2150 5050) $PN DD10
J 0
(-2140 5060);
DISPLAY 0.680851 (-2140 5060);
PAINT MONO (-2140 5060);
FORCEPROP 0 LASTPIN (-2150 4700) $PN DL10
J 0
(-2140 4710);
DISPLAY 0.680851 (-2140 4710);
PAINT MONO (-2140 4710);
FORCEPROP 0 LASTPIN (-2150 4350) $PN DV10
J 0
(-2140 4360);
DISPLAY 0.680851 (-2140 4360);
PAINT MONO (-2140 4360);
FORCEPROP 0 LASTPIN (-2150 4000) $PN EE10
J 0
(-2140 4010);
DISPLAY 0.680851 (-2140 4010);
PAINT MONO (-2140 4010);
FORCEPROP 0 LASTPIN (-2150 3650) $PN EM10
J 0
(-2140 3660);
DISPLAY 0.680851 (-2140 3660);
PAINT MONO (-2140 3660);
FORCEPROP 0 LASTPIN (-2150 3300) $PN EW10
J 0
(-2140 3310);
DISPLAY 0.680851 (-2140 3310);
PAINT MONO (-2140 3310);
FORCEPROP 0 LASTPIN (-2150 5850) $PN CH7
J 0
(-2140 5860);
DISPLAY 0.680851 (-2140 5860);
PAINT MONO (-2140 5860);
FORCEPROP 0 LASTPIN (-2150 5500) $PN CR7
J 0
(-2140 5510);
DISPLAY 0.680851 (-2140 5510);
PAINT MONO (-2140 5510);
FORCEPROP 0 LASTPIN (-2150 5150) $PN DB7
J 0
(-2140 5160);
DISPLAY 0.680851 (-2140 5160);
PAINT MONO (-2140 5160);
FORCEPROP 0 LASTPIN (-2150 4800) $PN DJ7
J 0
(-2140 4810);
DISPLAY 0.680851 (-2140 4810);
PAINT MONO (-2140 4810);
FORCEPROP 0 LASTPIN (-2150 4450) $PN DT7
J 0
(-2140 4460);
DISPLAY 0.680851 (-2140 4460);
PAINT MONO (-2140 4460);
FORCEPROP 0 LASTPIN (-2150 4100) $PN EC7
J 0
(-2140 4110);
DISPLAY 0.680851 (-2140 4110);
PAINT MONO (-2140 4110);
FORCEPROP 0 LASTPIN (-2150 3750) $PN EK7
J 0
(-2140 3760);
DISPLAY 0.680851 (-2140 3760);
PAINT MONO (-2140 3760);
FORCEPROP 0 LASTPIN (-2150 3400) $PN EU7
J 0
(-2140 3410);
DISPLAY 0.680851 (-2140 3410);
PAINT MONO (-2140 3410);
FORCEPROP 1 LAST MATERIAL IC
J 0
(-2950 6075);
DISPLAY 0.723404 (-2950 6075);
PAINT GREEN (-2950 6075);
FORCEPROP 2 LAST VALUE PT5161LRS
J 0
(-2950 6275);
DISPLAY 0.680851 (-2950 6275);
FORCEPROP 2 LAST PART_TYPE SMLF
J 0
(-2950 6325);
DISPLAY 0.680851 (-2950 6325);
FORCEPROP 1 LAST NEEDS_NO_SIZE TRUE
J 0
(-2600 4600);
DISPLAY 0.723404 (-2600 4600);
PAINT GREEN (-2600 4600);
DISPLAY INVISIBLE (-2600 4600);
FORCEPROP 1 LAST CDS_LMAN_SYM_OUTLINE -350,1450,300,-1400
J 0
(-2600 4600);
DISPLAY 0.468085 (-2600 4600);
PAINT GREEN (-2600 4600);
DISPLAY INVISIBLE (-2600 4600);
FORCEPROP 2 LAST CDS_LIB pure_quanta
J 0
(-2600 4600);
DISPLAY INVISIBLE (-2600 4600);
FORCEPROP 1 LAST PATH I142
J 0
(-2600 4600);
DISPLAY 0.723404 (-2600 4600);
PAINT GREEN (-2600 4600);
DISPLAY INVISIBLE (-2600 4600);
FORCEPROP 1 LAST PART_NUMBER AJ051610U03
J 0
(-2950 6150);
DISPLAY 0.723404 (-2950 6150);
PAINT GREEN (-2950 6150);
DISPLAY INVISIBLE (-2950 6150);
FORCEADD TAP..1
R 2
(-3050 1775);
FORCEPROP 3 LASTPIN (-3000 1775) SIG_NAME P5E_CPU1_P2_TX_BUF_DP<2>
J 0
(-2990 1785);
DISPLAY 0.659574 (-2990 1785);
PAINT MONO (-2990 1785);
DISPLAY INVISIBLE (-2990 1785);
FORCEPROP 1 LASTPIN (-3000 1775) BN 2
J 2
(-2988 1783);
DISPLAY 0.680851 (-2988 1783);
PAINT GREEN (-2988 1783);
FORCEPROP 2 LAST CDS_LIB standard
J 0
(-3050 1775);
DISPLAY INVISIBLE (-3050 1775);
FORCEPROP 1 LAST BODY_TYPE PLUMBING
J 2
(-3050 1825);
DISPLAY 0.872340 (-3050 1825);
PAINT GREEN (-3050 1825);
DISPLAY INVISIBLE (-3050 1825);
FORCEPROP 1 LAST HDL_TAP TRUE
J 2
(-3375 1650);
DISPLAY 0.872340 (-3375 1650);
DISPLAY INVISIBLE (-3375 1650);
FORCEPROP 1 LAST PATH I15
J 2
(-3048 1775);
DISPLAY 0.872340 (-3048 1775);
PAINT GREEN (-3048 1775);
DISPLAY INVISIBLE (-3048 1775);
FORCEADD TAP..1
R 2
(-3050 1975);
FORCEPROP 3 LASTPIN (-3000 1975) SIG_NAME P5E_CPU1_P2_TX_BUF_DP<1>
J 0
(-2990 1985);
DISPLAY 0.659574 (-2990 1985);
PAINT MONO (-2990 1985);
DISPLAY INVISIBLE (-2990 1985);
FORCEPROP 1 LASTPIN (-3000 1975) BN 1
J 2
(-2988 1983);
DISPLAY 0.680851 (-2988 1983);
PAINT GREEN (-2988 1983);
FORCEPROP 2 LAST CDS_LIB standard
J 0
(-3050 1975);
DISPLAY INVISIBLE (-3050 1975);
FORCEPROP 1 LAST BODY_TYPE PLUMBING
J 2
(-3050 2025);
DISPLAY 0.872340 (-3050 2025);
PAINT GREEN (-3050 2025);
DISPLAY INVISIBLE (-3050 2025);
FORCEPROP 1 LAST HDL_TAP TRUE
J 2
(-3375 1850);
DISPLAY 0.872340 (-3375 1850);
DISPLAY INVISIBLE (-3375 1850);
FORCEPROP 1 LAST PATH I16
J 2
(-3048 1975);
DISPLAY 0.872340 (-3048 1975);
PAINT GREEN (-3048 1975);
DISPLAY INVISIBLE (-3048 1975);
FORCEADD Q_CAP_DIFFBUS..2
R 2
(-2325 725);
FORCEPROP 1 LAST LOCATION C6708
J 2
(-2050 725);
DISPLAY 0.723404 (-2050 725);
PAINT GREEN (-2050 725);
FORCEPROP 2 LAST $SEC 1
J 2
(-2150 800);
DISPLAY 0.680851 (-2150 800);
PAINT MONO (-2150 800);
DISPLAY INVISIBLE (-2150 800);
FORCEPROP 2 LAST CDS_SEC 1
J 2
(-2150 800);
DISPLAY 0.680851 (-2150 800);
DISPLAY INVISIBLE (-2150 800);
FORCEPROP 2 LASTPIN (-2250 725) $PN 1
J 0
(-2240 735);
DISPLAY 0.808511 (-2240 735);
FORCEPROP 2 LASTPIN (-2400 725) $PN 2
J 2
(-2410 735);
DISPLAY 0.808511 (-2410 735);
FORCEPROP 2 LAST VALUE DIFF BUS_0.22UF
J 2
(-2475 725);
DISPLAY 0.553191 (-2475 725);
FORCEPROP 2 LAST TOLERANCE 20%
J 2
(-2400 775);
DISPLAY 0.553191 (-2400 775);
DISPLAY INVISIBLE (-2400 775);
FORCEPROP 2 LAST PACK_TYPE C0201
J 2
(-2500 775);
DISPLAY 0.553191 (-2500 775);
DISPLAY INVISIBLE (-2500 775);
FORCEPROP 1 LAST MATERIAL X6S
J 2
(-2316 804);
DISPLAY 0.574468 (-2316 804);
PAINT GREEN (-2316 804);
DISPLAY INVISIBLE (-2316 804);
FORCEPROP 2 LAST VOLTAGE 6.3V
J 2
(-2675 775);
DISPLAY 0.553191 (-2675 775);
DISPLAY INVISIBLE (-2675 775);
FORCEPROP 1 LAST PIN_NAMES_ROTATE TRUE
J 2
(-2325 725);
DISPLAY 0.489362 (-2325 725);
PAINT GREEN (-2325 725);
DISPLAY INVISIBLE (-2325 725);
FORCEPROP 2 LAST CDS_LIB pure_quanta
J 2
(-2325 725);
DISPLAY INVISIBLE (-2325 725);
FORCEPROP 1 LAST CDS_LMAN_SYM_OUTLINE -25,50,25,-50
J 2
(-2325 725);
DISPLAY 0.468085 (-2325 725);
PAINT GREEN (-2325 725);
DISPLAY INVISIBLE (-2325 725);
FORCEPROP 1 LAST PATH I17
J 2
(-2325 725);
DISPLAY 0.723404 (-2325 725);
DISPLAY INVISIBLE (-2325 725);
FORCEPROP 1 LAST PART_NUMBER SP_CH4221MEE01
J 2
(-2441 813);
DISPLAY 0.574468 (-2441 813);
PAINT GREEN (-2441 813);
DISPLAY INVISIBLE (-2441 813);
FORCEPROP 1 LAST LOCATION C6708
J 0
(-2075 800);
DISPLAY 1.021277 (-2075 800);
DISPLAY INVISIBLE (-2075 800);
FORCEADD Q_CAP_DIFFBUS..2
R 2
(-2325 775);
FORCEPROP 1 LAST LOCATION C6707
J 2
(-2050 775);
DISPLAY 0.723404 (-2050 775);
PAINT GREEN (-2050 775);
FORCEPROP 2 LAST $SEC 1
J 2
(-2150 850);
DISPLAY 0.680851 (-2150 850);
PAINT MONO (-2150 850);
DISPLAY INVISIBLE (-2150 850);
FORCEPROP 2 LAST CDS_SEC 1
J 2
(-2150 850);
DISPLAY 0.680851 (-2150 850);
DISPLAY INVISIBLE (-2150 850);
FORCEPROP 2 LASTPIN (-2250 775) $PN 1
J 0
(-2240 785);
DISPLAY 0.808511 (-2240 785);
FORCEPROP 2 LASTPIN (-2400 775) $PN 2
J 2
(-2410 785);
DISPLAY 0.808511 (-2410 785);
FORCEPROP 2 LAST VALUE DIFF BUS_0.22UF
J 2
(-2475 775);
DISPLAY 0.553191 (-2475 775);
FORCEPROP 2 LAST TOLERANCE 20%
J 2
(-2400 825);
DISPLAY 0.553191 (-2400 825);
DISPLAY INVISIBLE (-2400 825);
FORCEPROP 2 LAST PACK_TYPE C0201
J 2
(-2500 825);
DISPLAY 0.553191 (-2500 825);
DISPLAY INVISIBLE (-2500 825);
FORCEPROP 1 LAST MATERIAL X6S
J 2
(-2316 854);
DISPLAY 0.574468 (-2316 854);
PAINT GREEN (-2316 854);
DISPLAY INVISIBLE (-2316 854);
FORCEPROP 2 LAST VOLTAGE 6.3V
J 2
(-2675 825);
DISPLAY 0.553191 (-2675 825);
DISPLAY INVISIBLE (-2675 825);
FORCEPROP 1 LAST PIN_NAMES_ROTATE TRUE
J 2
(-2325 775);
DISPLAY 0.489362 (-2325 775);
PAINT GREEN (-2325 775);
DISPLAY INVISIBLE (-2325 775);
FORCEPROP 2 LAST CDS_LIB pure_quanta
J 2
(-2325 775);
DISPLAY INVISIBLE (-2325 775);
FORCEPROP 1 LAST CDS_LMAN_SYM_OUTLINE -25,50,25,-50
J 2
(-2325 775);
DISPLAY 0.468085 (-2325 775);
PAINT GREEN (-2325 775);
DISPLAY INVISIBLE (-2325 775);
FORCEPROP 1 LAST PATH I18
J 2
(-2325 775);
DISPLAY 0.723404 (-2325 775);
DISPLAY INVISIBLE (-2325 775);
FORCEPROP 1 LAST PART_NUMBER SP_CH4221MEE01
J 2
(-2441 863);
DISPLAY 0.574468 (-2441 863);
PAINT GREEN (-2441 863);
DISPLAY INVISIBLE (-2441 863);
FORCEPROP 1 LAST LOCATION C6707
J 0
(-2075 850);
DISPLAY 1.021277 (-2075 850);
DISPLAY INVISIBLE (-2075 850);
FORCEADD Q_CAP_DIFFBUS..2
R 2
(-2325 925);
FORCEPROP 1 LAST LOCATION C6706
J 2
(-2050 925);
DISPLAY 0.723404 (-2050 925);
PAINT GREEN (-2050 925);
FORCEPROP 2 LAST $SEC 1
J 2
(-2150 1000);
DISPLAY 0.680851 (-2150 1000);
PAINT MONO (-2150 1000);
DISPLAY INVISIBLE (-2150 1000);
FORCEPROP 2 LAST CDS_SEC 1
J 2
(-2150 1000);
DISPLAY 0.680851 (-2150 1000);
DISPLAY INVISIBLE (-2150 1000);
FORCEPROP 2 LASTPIN (-2250 925) $PN 1
J 0
(-2240 935);
DISPLAY 0.808511 (-2240 935);
FORCEPROP 2 LASTPIN (-2400 925) $PN 2
J 2
(-2410 935);
DISPLAY 0.808511 (-2410 935);
FORCEPROP 2 LAST VALUE DIFF BUS_0.22UF
J 2
(-2475 925);
DISPLAY 0.553191 (-2475 925);
FORCEPROP 2 LAST TOLERANCE 20%
J 2
(-2400 975);
DISPLAY 0.553191 (-2400 975);
DISPLAY INVISIBLE (-2400 975);
FORCEPROP 2 LAST PACK_TYPE C0201
J 2
(-2500 975);
DISPLAY 0.553191 (-2500 975);
DISPLAY INVISIBLE (-2500 975);
FORCEPROP 1 LAST MATERIAL X6S
J 2
(-2316 1004);
DISPLAY 0.574468 (-2316 1004);
PAINT GREEN (-2316 1004);
DISPLAY INVISIBLE (-2316 1004);
FORCEPROP 2 LAST VOLTAGE 6.3V
J 2
(-2675 975);
DISPLAY 0.553191 (-2675 975);
DISPLAY INVISIBLE (-2675 975);
FORCEPROP 1 LAST PIN_NAMES_ROTATE TRUE
J 2
(-2325 925);
DISPLAY 0.489362 (-2325 925);
PAINT GREEN (-2325 925);
DISPLAY INVISIBLE (-2325 925);
FORCEPROP 2 LAST CDS_LIB pure_quanta
J 2
(-2325 925);
DISPLAY INVISIBLE (-2325 925);
FORCEPROP 1 LAST CDS_LMAN_SYM_OUTLINE -25,50,25,-50
J 2
(-2325 925);
DISPLAY 0.468085 (-2325 925);
PAINT GREEN (-2325 925);
DISPLAY INVISIBLE (-2325 925);
FORCEPROP 1 LAST PATH I19
J 2
(-2325 925);
DISPLAY 0.723404 (-2325 925);
DISPLAY INVISIBLE (-2325 925);
FORCEPROP 1 LAST PART_NUMBER SP_CH4221MEE01
J 2
(-2441 1013);
DISPLAY 0.574468 (-2441 1013);
PAINT GREEN (-2441 1013);
DISPLAY INVISIBLE (-2441 1013);
FORCEPROP 1 LAST LOCATION C6706
J 0
(-2075 1000);
DISPLAY 1.021277 (-2075 1000);
DISPLAY INVISIBLE (-2075 1000);
FORCEADD OFFPAGE..1
(-4250 2150);
FORCEPROP 2 LAST $XR0 342 
J 0
(-4502 2150);
DISPLAY 0.638298 (-4502 2150);
PAINT MONO (-4502 2150);
FORCEPROP 2 LAST CDS_LIB standard
J 0
(-4250 2150);
DISPLAY INVISIBLE (-4250 2150);
FORCEPROP 1 LAST OFFPAGE TRUE
J 0
(-3925 2025);
DISPLAY 0.872340 (-3925 2025);
DISPLAY INVISIBLE (-3925 2025);
FORCEPROP 1 LAST COMMENT_BODY TRUE
J 0
(-4125 2050);
DISPLAY 0.872340 (-4125 2050);
PAINT GREEN (-4125 2050);
DISPLAY INVISIBLE (-4125 2050);
FORCEPROP 2 LAST PATH I2
J 0
(-4500 2200);
DISPLAY 0.680851 (-4500 2200);
DISPLAY INVISIBLE (-4500 2200);
FORCEADD Q_CAP_DIFFBUS..2
R 2
(-2325 975);
FORCEPROP 1 LAST LOCATION C6705
J 2
(-2050 975);
DISPLAY 0.723404 (-2050 975);
PAINT GREEN (-2050 975);
FORCEPROP 2 LAST $SEC 1
J 2
(-2150 1050);
DISPLAY 0.680851 (-2150 1050);
PAINT MONO (-2150 1050);
DISPLAY INVISIBLE (-2150 1050);
FORCEPROP 2 LAST CDS_SEC 1
J 2
(-2150 1050);
DISPLAY 0.680851 (-2150 1050);
DISPLAY INVISIBLE (-2150 1050);
FORCEPROP 2 LASTPIN (-2250 975) $PN 1
J 0
(-2240 985);
DISPLAY 0.808511 (-2240 985);
FORCEPROP 2 LASTPIN (-2400 975) $PN 2
J 2
(-2410 985);
DISPLAY 0.808511 (-2410 985);
FORCEPROP 2 LAST VALUE DIFF BUS_0.22UF
J 2
(-2475 975);
DISPLAY 0.553191 (-2475 975);
FORCEPROP 2 LAST TOLERANCE 20%
J 2
(-2400 1025);
DISPLAY 0.553191 (-2400 1025);
DISPLAY INVISIBLE (-2400 1025);
FORCEPROP 2 LAST PACK_TYPE C0201
J 2
(-2500 1025);
DISPLAY 0.553191 (-2500 1025);
DISPLAY INVISIBLE (-2500 1025);
FORCEPROP 1 LAST MATERIAL X6S
J 2
(-2316 1054);
DISPLAY 0.574468 (-2316 1054);
PAINT GREEN (-2316 1054);
DISPLAY INVISIBLE (-2316 1054);
FORCEPROP 2 LAST VOLTAGE 6.3V
J 2
(-2675 1025);
DISPLAY 0.553191 (-2675 1025);
DISPLAY INVISIBLE (-2675 1025);
FORCEPROP 1 LAST PIN_NAMES_ROTATE TRUE
J 2
(-2325 975);
DISPLAY 0.489362 (-2325 975);
PAINT GREEN (-2325 975);
DISPLAY INVISIBLE (-2325 975);
FORCEPROP 1 LAST CDS_LMAN_SYM_OUTLINE -25,50,25,-50
J 2
(-2325 975);
DISPLAY 0.468085 (-2325 975);
PAINT GREEN (-2325 975);
DISPLAY INVISIBLE (-2325 975);
FORCEPROP 2 LAST CDS_LIB pure_quanta
J 2
(-2325 975);
DISPLAY INVISIBLE (-2325 975);
FORCEPROP 1 LAST PATH I20
J 2
(-2325 975);
DISPLAY 0.723404 (-2325 975);
DISPLAY INVISIBLE (-2325 975);
FORCEPROP 1 LAST PART_NUMBER SP_CH4221MEE01
J 2
(-2441 1063);
DISPLAY 0.574468 (-2441 1063);
PAINT GREEN (-2441 1063);
DISPLAY INVISIBLE (-2441 1063);
FORCEPROP 1 LAST LOCATION C6705
J 0
(-2075 1050);
DISPLAY 1.021277 (-2075 1050);
DISPLAY INVISIBLE (-2075 1050);
FORCEADD Q_CAP_DIFFBUS..2
R 2
(-2325 1125);
FORCEPROP 1 LAST LOCATION C6704
J 2
(-2050 1125);
DISPLAY 0.723404 (-2050 1125);
PAINT GREEN (-2050 1125);
FORCEPROP 2 LAST $SEC 1
J 2
(-2150 1200);
DISPLAY 0.680851 (-2150 1200);
PAINT MONO (-2150 1200);
DISPLAY INVISIBLE (-2150 1200);
FORCEPROP 2 LAST CDS_SEC 1
J 2
(-2150 1200);
DISPLAY 0.680851 (-2150 1200);
DISPLAY INVISIBLE (-2150 1200);
FORCEPROP 2 LASTPIN (-2250 1125) $PN 1
J 0
(-2240 1135);
DISPLAY 0.808511 (-2240 1135);
FORCEPROP 2 LASTPIN (-2400 1125) $PN 2
J 2
(-2410 1135);
DISPLAY 0.808511 (-2410 1135);
FORCEPROP 2 LAST VALUE DIFF BUS_0.22UF
J 2
(-2475 1125);
DISPLAY 0.553191 (-2475 1125);
FORCEPROP 2 LAST TOLERANCE 20%
J 2
(-2400 1175);
DISPLAY 0.553191 (-2400 1175);
DISPLAY INVISIBLE (-2400 1175);
FORCEPROP 2 LAST PACK_TYPE C0201
J 2
(-2500 1175);
DISPLAY 0.553191 (-2500 1175);
DISPLAY INVISIBLE (-2500 1175);
FORCEPROP 1 LAST MATERIAL X6S
J 2
(-2316 1204);
DISPLAY 0.574468 (-2316 1204);
PAINT GREEN (-2316 1204);
DISPLAY INVISIBLE (-2316 1204);
FORCEPROP 2 LAST VOLTAGE 6.3V
J 2
(-2675 1175);
DISPLAY 0.553191 (-2675 1175);
DISPLAY INVISIBLE (-2675 1175);
FORCEPROP 1 LAST PIN_NAMES_ROTATE TRUE
J 2
(-2325 1125);
DISPLAY 0.489362 (-2325 1125);
PAINT GREEN (-2325 1125);
DISPLAY INVISIBLE (-2325 1125);
FORCEPROP 2 LAST CDS_LIB pure_quanta
J 2
(-2325 1125);
DISPLAY INVISIBLE (-2325 1125);
FORCEPROP 1 LAST CDS_LMAN_SYM_OUTLINE -25,50,25,-50
J 2
(-2325 1125);
DISPLAY 0.468085 (-2325 1125);
PAINT GREEN (-2325 1125);
DISPLAY INVISIBLE (-2325 1125);
FORCEPROP 1 LAST PATH I21
J 2
(-2325 1125);
DISPLAY 0.723404 (-2325 1125);
DISPLAY INVISIBLE (-2325 1125);
FORCEPROP 1 LAST PART_NUMBER SP_CH4221MEE01
J 2
(-2441 1213);
DISPLAY 0.574468 (-2441 1213);
PAINT GREEN (-2441 1213);
DISPLAY INVISIBLE (-2441 1213);
FORCEPROP 1 LAST LOCATION C6704
J 0
(-2075 1200);
DISPLAY 1.021277 (-2075 1200);
DISPLAY INVISIBLE (-2075 1200);
FORCEADD Q_CAP_DIFFBUS..2
R 2
(-2325 1175);
FORCEPROP 1 LAST LOCATION C6703
J 2
(-2050 1175);
DISPLAY 0.723404 (-2050 1175);
PAINT GREEN (-2050 1175);
FORCEPROP 2 LAST $SEC 1
J 2
(-2150 1250);
DISPLAY 0.680851 (-2150 1250);
PAINT MONO (-2150 1250);
DISPLAY INVISIBLE (-2150 1250);
FORCEPROP 2 LAST CDS_SEC 1
J 2
(-2150 1250);
DISPLAY 0.680851 (-2150 1250);
DISPLAY INVISIBLE (-2150 1250);
FORCEPROP 2 LASTPIN (-2250 1175) $PN 1
J 0
(-2240 1185);
DISPLAY 0.808511 (-2240 1185);
FORCEPROP 2 LASTPIN (-2400 1175) $PN 2
J 2
(-2410 1185);
DISPLAY 0.808511 (-2410 1185);
FORCEPROP 2 LAST VALUE DIFF BUS_0.22UF
J 2
(-2475 1175);
DISPLAY 0.553191 (-2475 1175);
FORCEPROP 2 LAST TOLERANCE 20%
J 2
(-2400 1225);
DISPLAY 0.553191 (-2400 1225);
DISPLAY INVISIBLE (-2400 1225);
FORCEPROP 2 LAST PACK_TYPE C0201
J 2
(-2500 1225);
DISPLAY 0.553191 (-2500 1225);
DISPLAY INVISIBLE (-2500 1225);
FORCEPROP 1 LAST MATERIAL X6S
J 2
(-2316 1254);
DISPLAY 0.574468 (-2316 1254);
PAINT GREEN (-2316 1254);
DISPLAY INVISIBLE (-2316 1254);
FORCEPROP 2 LAST VOLTAGE 6.3V
J 2
(-2675 1225);
DISPLAY 0.553191 (-2675 1225);
DISPLAY INVISIBLE (-2675 1225);
FORCEPROP 1 LAST PIN_NAMES_ROTATE TRUE
J 2
(-2325 1175);
DISPLAY 0.489362 (-2325 1175);
PAINT GREEN (-2325 1175);
DISPLAY INVISIBLE (-2325 1175);
FORCEPROP 2 LAST CDS_LIB pure_quanta
J 2
(-2325 1175);
DISPLAY INVISIBLE (-2325 1175);
FORCEPROP 1 LAST CDS_LMAN_SYM_OUTLINE -25,50,25,-50
J 2
(-2325 1175);
DISPLAY 0.468085 (-2325 1175);
PAINT GREEN (-2325 1175);
DISPLAY INVISIBLE (-2325 1175);
FORCEPROP 1 LAST PATH I22
J 2
(-2325 1175);
DISPLAY 0.723404 (-2325 1175);
DISPLAY INVISIBLE (-2325 1175);
FORCEPROP 1 LAST PART_NUMBER SP_CH4221MEE01
J 2
(-2441 1263);
DISPLAY 0.574468 (-2441 1263);
PAINT GREEN (-2441 1263);
DISPLAY INVISIBLE (-2441 1263);
FORCEPROP 1 LAST LOCATION C6703
J 0
(-2075 1250);
DISPLAY 1.021277 (-2075 1250);
DISPLAY INVISIBLE (-2075 1250);
FORCEADD Q_CAP_DIFFBUS..2
R 2
(-2325 1325);
FORCEPROP 1 LAST LOCATION C6702
J 2
(-2050 1325);
DISPLAY 0.723404 (-2050 1325);
PAINT GREEN (-2050 1325);
FORCEPROP 2 LAST $SEC 1
J 2
(-2150 1400);
DISPLAY 0.680851 (-2150 1400);
PAINT MONO (-2150 1400);
DISPLAY INVISIBLE (-2150 1400);
FORCEPROP 2 LAST CDS_SEC 1
J 2
(-2150 1400);
DISPLAY 0.680851 (-2150 1400);
DISPLAY INVISIBLE (-2150 1400);
FORCEPROP 2 LASTPIN (-2250 1325) $PN 1
J 0
(-2240 1335);
DISPLAY 0.808511 (-2240 1335);
FORCEPROP 2 LASTPIN (-2400 1325) $PN 2
J 2
(-2410 1335);
DISPLAY 0.808511 (-2410 1335);
FORCEPROP 2 LAST VALUE DIFF BUS_0.22UF
J 2
(-2475 1325);
DISPLAY 0.553191 (-2475 1325);
FORCEPROP 2 LAST TOLERANCE 20%
J 2
(-2400 1375);
DISPLAY 0.553191 (-2400 1375);
DISPLAY INVISIBLE (-2400 1375);
FORCEPROP 2 LAST PACK_TYPE C0201
J 2
(-2500 1375);
DISPLAY 0.553191 (-2500 1375);
DISPLAY INVISIBLE (-2500 1375);
FORCEPROP 1 LAST MATERIAL X6S
J 2
(-2316 1404);
DISPLAY 0.574468 (-2316 1404);
PAINT GREEN (-2316 1404);
DISPLAY INVISIBLE (-2316 1404);
FORCEPROP 2 LAST VOLTAGE 6.3V
J 2
(-2675 1375);
DISPLAY 0.553191 (-2675 1375);
DISPLAY INVISIBLE (-2675 1375);
FORCEPROP 1 LAST PIN_NAMES_ROTATE TRUE
J 2
(-2325 1325);
DISPLAY 0.489362 (-2325 1325);
PAINT GREEN (-2325 1325);
DISPLAY INVISIBLE (-2325 1325);
FORCEPROP 1 LAST CDS_LMAN_SYM_OUTLINE -25,50,25,-50
J 2
(-2325 1325);
DISPLAY 0.468085 (-2325 1325);
PAINT GREEN (-2325 1325);
DISPLAY INVISIBLE (-2325 1325);
FORCEPROP 2 LAST CDS_LIB pure_quanta
J 2
(-2325 1325);
DISPLAY INVISIBLE (-2325 1325);
FORCEPROP 1 LAST PATH I23
J 2
(-2325 1325);
DISPLAY 0.723404 (-2325 1325);
DISPLAY INVISIBLE (-2325 1325);
FORCEPROP 1 LAST PART_NUMBER SP_CH4221MEE01
J 2
(-2441 1413);
DISPLAY 0.574468 (-2441 1413);
PAINT GREEN (-2441 1413);
DISPLAY INVISIBLE (-2441 1413);
FORCEPROP 1 LAST LOCATION C6702
J 0
(-2075 1400);
DISPLAY 1.021277 (-2075 1400);
DISPLAY INVISIBLE (-2075 1400);
FORCEADD Q_CAP_DIFFBUS..2
R 2
(-2325 1375);
FORCEPROP 1 LAST LOCATION C6701
J 2
(-2050 1375);
DISPLAY 0.723404 (-2050 1375);
PAINT GREEN (-2050 1375);
FORCEPROP 2 LAST $SEC 1
J 2
(-2150 1450);
DISPLAY 0.680851 (-2150 1450);
PAINT MONO (-2150 1450);
DISPLAY INVISIBLE (-2150 1450);
FORCEPROP 2 LAST CDS_SEC 1
J 2
(-2150 1450);
DISPLAY 0.680851 (-2150 1450);
DISPLAY INVISIBLE (-2150 1450);
FORCEPROP 2 LASTPIN (-2250 1375) $PN 1
J 0
(-2240 1385);
DISPLAY 0.808511 (-2240 1385);
FORCEPROP 2 LASTPIN (-2400 1375) $PN 2
J 2
(-2410 1385);
DISPLAY 0.808511 (-2410 1385);
FORCEPROP 2 LAST VALUE DIFF BUS_0.22UF
J 2
(-2475 1375);
DISPLAY 0.553191 (-2475 1375);
FORCEPROP 2 LAST TOLERANCE 20%
J 2
(-2400 1425);
DISPLAY 0.553191 (-2400 1425);
DISPLAY INVISIBLE (-2400 1425);
FORCEPROP 2 LAST PACK_TYPE C0201
J 2
(-2500 1425);
DISPLAY 0.553191 (-2500 1425);
DISPLAY INVISIBLE (-2500 1425);
FORCEPROP 1 LAST MATERIAL X6S
J 2
(-2316 1454);
DISPLAY 0.574468 (-2316 1454);
PAINT GREEN (-2316 1454);
DISPLAY INVISIBLE (-2316 1454);
FORCEPROP 2 LAST VOLTAGE 6.3V
J 2
(-2675 1425);
DISPLAY 0.553191 (-2675 1425);
DISPLAY INVISIBLE (-2675 1425);
FORCEPROP 1 LAST PIN_NAMES_ROTATE TRUE
J 2
(-2325 1375);
DISPLAY 0.489362 (-2325 1375);
PAINT GREEN (-2325 1375);
DISPLAY INVISIBLE (-2325 1375);
FORCEPROP 1 LAST CDS_LMAN_SYM_OUTLINE -25,50,25,-50
J 2
(-2325 1375);
DISPLAY 0.468085 (-2325 1375);
PAINT GREEN (-2325 1375);
DISPLAY INVISIBLE (-2325 1375);
FORCEPROP 2 LAST CDS_LIB pure_quanta
J 2
(-2325 1375);
DISPLAY INVISIBLE (-2325 1375);
FORCEPROP 1 LAST PATH I24
J 2
(-2325 1375);
DISPLAY 0.723404 (-2325 1375);
DISPLAY INVISIBLE (-2325 1375);
FORCEPROP 1 LAST PART_NUMBER SP_CH4221MEE01
J 2
(-2441 1463);
DISPLAY 0.574468 (-2441 1463);
PAINT GREEN (-2441 1463);
DISPLAY INVISIBLE (-2441 1463);
FORCEPROP 1 LAST LOCATION C6701
J 0
(-2075 1450);
DISPLAY 1.021277 (-2075 1450);
DISPLAY INVISIBLE (-2075 1450);
FORCEADD Q_CAP_DIFFBUS..2
R 2
(-2325 1575);
FORCEPROP 1 LAST LOCATION C6699
J 2
(-2050 1575);
DISPLAY 0.723404 (-2050 1575);
PAINT GREEN (-2050 1575);
FORCEPROP 2 LAST $SEC 1
J 2
(-2150 1650);
DISPLAY 0.680851 (-2150 1650);
PAINT MONO (-2150 1650);
DISPLAY INVISIBLE (-2150 1650);
FORCEPROP 2 LAST CDS_SEC 1
J 2
(-2150 1650);
DISPLAY 0.680851 (-2150 1650);
DISPLAY INVISIBLE (-2150 1650);
FORCEPROP 2 LASTPIN (-2250 1575) $PN 1
J 0
(-2240 1585);
DISPLAY 0.808511 (-2240 1585);
FORCEPROP 2 LASTPIN (-2400 1575) $PN 2
J 2
(-2410 1585);
DISPLAY 0.808511 (-2410 1585);
FORCEPROP 2 LAST VALUE DIFF BUS_0.22UF
J 2
(-2475 1575);
DISPLAY 0.553191 (-2475 1575);
FORCEPROP 2 LAST TOLERANCE 20%
J 2
(-2400 1625);
DISPLAY 0.553191 (-2400 1625);
DISPLAY INVISIBLE (-2400 1625);
FORCEPROP 2 LAST PACK_TYPE C0201
J 2
(-2500 1625);
DISPLAY 0.553191 (-2500 1625);
DISPLAY INVISIBLE (-2500 1625);
FORCEPROP 1 LAST MATERIAL X6S
J 2
(-2316 1654);
DISPLAY 0.574468 (-2316 1654);
PAINT GREEN (-2316 1654);
DISPLAY INVISIBLE (-2316 1654);
FORCEPROP 2 LAST VOLTAGE 6.3V
J 2
(-2675 1625);
DISPLAY 0.553191 (-2675 1625);
DISPLAY INVISIBLE (-2675 1625);
FORCEPROP 1 LAST PIN_NAMES_ROTATE TRUE
J 2
(-2325 1575);
DISPLAY 0.489362 (-2325 1575);
PAINT GREEN (-2325 1575);
DISPLAY INVISIBLE (-2325 1575);
FORCEPROP 2 LAST CDS_LIB pure_quanta
J 2
(-2325 1575);
DISPLAY INVISIBLE (-2325 1575);
FORCEPROP 1 LAST CDS_LMAN_SYM_OUTLINE -25,50,25,-50
J 2
(-2325 1575);
DISPLAY 0.468085 (-2325 1575);
PAINT GREEN (-2325 1575);
DISPLAY INVISIBLE (-2325 1575);
FORCEPROP 1 LAST PATH I25
J 2
(-2325 1575);
DISPLAY 0.723404 (-2325 1575);
DISPLAY INVISIBLE (-2325 1575);
FORCEPROP 1 LAST PART_NUMBER SP_CH4221MEE01
J 2
(-2441 1663);
DISPLAY 0.574468 (-2441 1663);
PAINT GREEN (-2441 1663);
DISPLAY INVISIBLE (-2441 1663);
FORCEPROP 1 LAST LOCATION C6699
J 0
(-2075 1650);
DISPLAY 1.021277 (-2075 1650);
DISPLAY INVISIBLE (-2075 1650);
FORCEADD Q_CAP_DIFFBUS..2
R 2
(-2325 1525);
FORCEPROP 1 LAST LOCATION C6700
J 2
(-2050 1525);
DISPLAY 0.723404 (-2050 1525);
PAINT GREEN (-2050 1525);
FORCEPROP 2 LAST $SEC 1
J 2
(-2150 1600);
DISPLAY 0.680851 (-2150 1600);
PAINT MONO (-2150 1600);
DISPLAY INVISIBLE (-2150 1600);
FORCEPROP 2 LAST CDS_SEC 1
J 2
(-2150 1600);
DISPLAY 0.680851 (-2150 1600);
DISPLAY INVISIBLE (-2150 1600);
FORCEPROP 2 LASTPIN (-2250 1525) $PN 1
J 0
(-2240 1535);
DISPLAY 0.808511 (-2240 1535);
FORCEPROP 2 LASTPIN (-2400 1525) $PN 2
J 2
(-2410 1535);
DISPLAY 0.808511 (-2410 1535);
FORCEPROP 2 LAST VALUE DIFF BUS_0.22UF
J 2
(-2475 1525);
DISPLAY 0.553191 (-2475 1525);
FORCEPROP 2 LAST TOLERANCE 20%
J 2
(-2400 1575);
DISPLAY 0.553191 (-2400 1575);
DISPLAY INVISIBLE (-2400 1575);
FORCEPROP 2 LAST PACK_TYPE C0201
J 2
(-2500 1575);
DISPLAY 0.553191 (-2500 1575);
DISPLAY INVISIBLE (-2500 1575);
FORCEPROP 1 LAST MATERIAL X6S
J 2
(-2316 1604);
DISPLAY 0.574468 (-2316 1604);
PAINT GREEN (-2316 1604);
DISPLAY INVISIBLE (-2316 1604);
FORCEPROP 2 LAST VOLTAGE 6.3V
J 2
(-2675 1575);
DISPLAY 0.553191 (-2675 1575);
DISPLAY INVISIBLE (-2675 1575);
FORCEPROP 1 LAST PIN_NAMES_ROTATE TRUE
J 2
(-2325 1525);
DISPLAY 0.489362 (-2325 1525);
PAINT GREEN (-2325 1525);
DISPLAY INVISIBLE (-2325 1525);
FORCEPROP 2 LAST CDS_LIB pure_quanta
J 2
(-2325 1525);
DISPLAY INVISIBLE (-2325 1525);
FORCEPROP 1 LAST CDS_LMAN_SYM_OUTLINE -25,50,25,-50
J 2
(-2325 1525);
DISPLAY 0.468085 (-2325 1525);
PAINT GREEN (-2325 1525);
DISPLAY INVISIBLE (-2325 1525);
FORCEPROP 1 LAST PATH I26
J 2
(-2325 1525);
DISPLAY 0.723404 (-2325 1525);
DISPLAY INVISIBLE (-2325 1525);
FORCEPROP 1 LAST PART_NUMBER SP_CH4221MEE01
J 2
(-2441 1613);
DISPLAY 0.574468 (-2441 1613);
PAINT GREEN (-2441 1613);
DISPLAY INVISIBLE (-2441 1613);
FORCEPROP 1 LAST LOCATION C6700
J 0
(-2075 1600);
DISPLAY 1.021277 (-2075 1600);
DISPLAY INVISIBLE (-2075 1600);
FORCEADD Q_CAP_DIFFBUS..2
R 2
(-2325 1725);
FORCEPROP 1 LAST LOCATION C6698
J 2
(-2050 1725);
DISPLAY 0.723404 (-2050 1725);
PAINT GREEN (-2050 1725);
FORCEPROP 2 LAST $SEC 1
J 2
(-2150 1800);
DISPLAY 0.680851 (-2150 1800);
PAINT MONO (-2150 1800);
DISPLAY INVISIBLE (-2150 1800);
FORCEPROP 2 LAST CDS_SEC 1
J 2
(-2150 1800);
DISPLAY 0.680851 (-2150 1800);
DISPLAY INVISIBLE (-2150 1800);
FORCEPROP 2 LASTPIN (-2250 1725) $PN 1
J 0
(-2240 1735);
DISPLAY 0.808511 (-2240 1735);
FORCEPROP 2 LASTPIN (-2400 1725) $PN 2
J 2
(-2410 1735);
DISPLAY 0.808511 (-2410 1735);
FORCEPROP 2 LAST VALUE DIFF BUS_0.22UF
J 2
(-2475 1725);
DISPLAY 0.553191 (-2475 1725);
FORCEPROP 2 LAST TOLERANCE 20%
J 2
(-2400 1775);
DISPLAY 0.553191 (-2400 1775);
DISPLAY INVISIBLE (-2400 1775);
FORCEPROP 2 LAST PACK_TYPE C0201
J 2
(-2500 1775);
DISPLAY 0.553191 (-2500 1775);
DISPLAY INVISIBLE (-2500 1775);
FORCEPROP 1 LAST MATERIAL X6S
J 2
(-2316 1804);
DISPLAY 0.574468 (-2316 1804);
PAINT GREEN (-2316 1804);
DISPLAY INVISIBLE (-2316 1804);
FORCEPROP 2 LAST VOLTAGE 6.3V
J 2
(-2675 1775);
DISPLAY 0.553191 (-2675 1775);
DISPLAY INVISIBLE (-2675 1775);
FORCEPROP 1 LAST PIN_NAMES_ROTATE TRUE
J 2
(-2325 1725);
DISPLAY 0.489362 (-2325 1725);
PAINT GREEN (-2325 1725);
DISPLAY INVISIBLE (-2325 1725);
FORCEPROP 2 LAST CDS_LIB pure_quanta
J 2
(-2325 1725);
DISPLAY INVISIBLE (-2325 1725);
FORCEPROP 1 LAST CDS_LMAN_SYM_OUTLINE -25,50,25,-50
J 2
(-2325 1725);
DISPLAY 0.468085 (-2325 1725);
PAINT GREEN (-2325 1725);
DISPLAY INVISIBLE (-2325 1725);
FORCEPROP 1 LAST PATH I27
J 2
(-2325 1725);
DISPLAY 0.723404 (-2325 1725);
DISPLAY INVISIBLE (-2325 1725);
FORCEPROP 1 LAST PART_NUMBER SP_CH4221MEE01
J 2
(-2441 1813);
DISPLAY 0.574468 (-2441 1813);
PAINT GREEN (-2441 1813);
DISPLAY INVISIBLE (-2441 1813);
FORCEPROP 1 LAST LOCATION C6698
J 0
(-2075 1800);
DISPLAY 1.021277 (-2075 1800);
DISPLAY INVISIBLE (-2075 1800);
FORCEADD Q_CAP_DIFFBUS..2
R 2
(-2325 1925);
FORCEPROP 1 LAST LOCATION C6696
J 2
(-2025 1925);
DISPLAY 0.723404 (-2025 1925);
PAINT GREEN (-2025 1925);
FORCEPROP 2 LAST $SEC 1
J 2
(-2150 2000);
DISPLAY 0.680851 (-2150 2000);
PAINT MONO (-2150 2000);
DISPLAY INVISIBLE (-2150 2000);
FORCEPROP 2 LAST CDS_SEC 1
J 2
(-2150 2000);
DISPLAY 0.680851 (-2150 2000);
DISPLAY INVISIBLE (-2150 2000);
FORCEPROP 2 LASTPIN (-2250 1925) $PN 1
J 0
(-2240 1935);
DISPLAY 0.808511 (-2240 1935);
FORCEPROP 2 LASTPIN (-2400 1925) $PN 2
J 2
(-2410 1935);
DISPLAY 0.808511 (-2410 1935);
FORCEPROP 2 LAST VALUE DIFF BUS_0.22UF
J 2
(-2475 1925);
DISPLAY 0.553191 (-2475 1925);
FORCEPROP 2 LAST TOLERANCE 20%
J 2
(-2400 1975);
DISPLAY 0.553191 (-2400 1975);
DISPLAY INVISIBLE (-2400 1975);
FORCEPROP 2 LAST PACK_TYPE C0201
J 2
(-2500 1975);
DISPLAY 0.553191 (-2500 1975);
DISPLAY INVISIBLE (-2500 1975);
FORCEPROP 1 LAST MATERIAL X6S
J 2
(-2316 2004);
DISPLAY 0.574468 (-2316 2004);
PAINT GREEN (-2316 2004);
DISPLAY INVISIBLE (-2316 2004);
FORCEPROP 2 LAST VOLTAGE 6.3V
J 2
(-2675 1975);
DISPLAY 0.553191 (-2675 1975);
DISPLAY INVISIBLE (-2675 1975);
FORCEPROP 1 LAST PIN_NAMES_ROTATE TRUE
J 2
(-2325 1925);
DISPLAY 0.489362 (-2325 1925);
PAINT GREEN (-2325 1925);
DISPLAY INVISIBLE (-2325 1925);
FORCEPROP 2 LAST CDS_LIB pure_quanta
J 2
(-2325 1925);
DISPLAY INVISIBLE (-2325 1925);
FORCEPROP 1 LAST CDS_LMAN_SYM_OUTLINE -25,50,25,-50
J 2
(-2325 1925);
DISPLAY 0.468085 (-2325 1925);
PAINT GREEN (-2325 1925);
DISPLAY INVISIBLE (-2325 1925);
FORCEPROP 1 LAST PATH I28
J 2
(-2325 1925);
DISPLAY 0.723404 (-2325 1925);
DISPLAY INVISIBLE (-2325 1925);
FORCEPROP 1 LAST PART_NUMBER SP_CH4221MEE01
J 2
(-2441 2013);
DISPLAY 0.574468 (-2441 2013);
PAINT GREEN (-2441 2013);
DISPLAY INVISIBLE (-2441 2013);
FORCEPROP 1 LAST LOCATION C6696
J 0
(-2075 2000);
DISPLAY 1.021277 (-2075 2000);
DISPLAY INVISIBLE (-2075 2000);
FORCEADD Q_CAP_DIFFBUS..2
R 2
(-2325 1975);
FORCEPROP 1 LAST LOCATION C6695
J 2
(-2025 1975);
DISPLAY 0.723404 (-2025 1975);
PAINT GREEN (-2025 1975);
FORCEPROP 2 LAST $SEC 1
J 2
(-2150 2050);
DISPLAY 0.680851 (-2150 2050);
PAINT MONO (-2150 2050);
DISPLAY INVISIBLE (-2150 2050);
FORCEPROP 2 LAST CDS_SEC 1
J 2
(-2150 2050);
DISPLAY 0.680851 (-2150 2050);
DISPLAY INVISIBLE (-2150 2050);
FORCEPROP 2 LASTPIN (-2250 1975) $PN 1
J 0
(-2240 1985);
DISPLAY 0.808511 (-2240 1985);
FORCEPROP 2 LASTPIN (-2400 1975) $PN 2
J 2
(-2410 1985);
DISPLAY 0.808511 (-2410 1985);
FORCEPROP 2 LAST VALUE DIFF BUS_0.22UF
J 2
(-2475 1975);
DISPLAY 0.553191 (-2475 1975);
FORCEPROP 2 LAST TOLERANCE 20%
J 2
(-2400 2025);
DISPLAY 0.553191 (-2400 2025);
DISPLAY INVISIBLE (-2400 2025);
FORCEPROP 2 LAST PACK_TYPE C0201
J 2
(-2500 2025);
DISPLAY 0.553191 (-2500 2025);
DISPLAY INVISIBLE (-2500 2025);
FORCEPROP 1 LAST MATERIAL X6S
J 2
(-2316 2054);
DISPLAY 0.574468 (-2316 2054);
PAINT GREEN (-2316 2054);
DISPLAY INVISIBLE (-2316 2054);
FORCEPROP 2 LAST VOLTAGE 6.3V
J 2
(-2675 2025);
DISPLAY 0.553191 (-2675 2025);
DISPLAY INVISIBLE (-2675 2025);
FORCEPROP 1 LAST PIN_NAMES_ROTATE TRUE
J 2
(-2325 1975);
DISPLAY 0.489362 (-2325 1975);
PAINT GREEN (-2325 1975);
DISPLAY INVISIBLE (-2325 1975);
FORCEPROP 2 LAST CDS_LIB pure_quanta
J 2
(-2325 1975);
DISPLAY INVISIBLE (-2325 1975);
FORCEPROP 1 LAST CDS_LMAN_SYM_OUTLINE -25,50,25,-50
J 2
(-2325 1975);
DISPLAY 0.468085 (-2325 1975);
PAINT GREEN (-2325 1975);
DISPLAY INVISIBLE (-2325 1975);
FORCEPROP 1 LAST PATH I29
J 2
(-2325 1975);
DISPLAY 0.723404 (-2325 1975);
DISPLAY INVISIBLE (-2325 1975);
FORCEPROP 1 LAST PART_NUMBER SP_CH4221MEE01
J 2
(-2441 2063);
DISPLAY 0.574468 (-2441 2063);
PAINT GREEN (-2441 2063);
DISPLAY INVISIBLE (-2441 2063);
FORCEPROP 1 LAST LOCATION C6695
J 0
(-2075 2050);
DISPLAY 1.021277 (-2075 2050);
DISPLAY INVISIBLE (-2075 2050);
FORCEADD TAP..1
R 2
(-3300 725);
FORCEPROP 3 LASTPIN (-3250 725) SIG_NAME P5E_CPU1_P2_TX_BUF_DN<7>
J 0
(-3240 735);
DISPLAY 0.659574 (-3240 735);
PAINT MONO (-3240 735);
DISPLAY INVISIBLE (-3240 735);
FORCEPROP 1 LASTPIN (-3250 725) BN 7
J 2
(-3238 733);
DISPLAY 0.680851 (-3238 733);
PAINT GREEN (-3238 733);
FORCEPROP 2 LAST CDS_LIB standard
J 0
(-3300 725);
DISPLAY INVISIBLE (-3300 725);
FORCEPROP 1 LAST BODY_TYPE PLUMBING
J 2
(-3300 775);
DISPLAY 0.872340 (-3300 775);
PAINT GREEN (-3300 775);
DISPLAY INVISIBLE (-3300 775);
FORCEPROP 1 LAST HDL_TAP TRUE
J 2
(-3625 600);
DISPLAY 0.872340 (-3625 600);
DISPLAY INVISIBLE (-3625 600);
FORCEPROP 1 LAST PATH I3
J 2
(-3298 725);
DISPLAY 0.872340 (-3298 725);
PAINT GREEN (-3298 725);
DISPLAY INVISIBLE (-3298 725);
FORCEADD Q_CAP_DIFFBUS..2
R 2
(-2325 1775);
FORCEPROP 1 LAST LOCATION C6697
J 2
(-2050 1775);
DISPLAY 0.723404 (-2050 1775);
PAINT GREEN (-2050 1775);
FORCEPROP 2 LAST $SEC 1
J 2
(-2150 1850);
DISPLAY 0.680851 (-2150 1850);
PAINT MONO (-2150 1850);
DISPLAY INVISIBLE (-2150 1850);
FORCEPROP 2 LAST CDS_SEC 1
J 2
(-2150 1850);
DISPLAY 0.680851 (-2150 1850);
DISPLAY INVISIBLE (-2150 1850);
FORCEPROP 2 LASTPIN (-2250 1775) $PN 1
J 0
(-2240 1785);
DISPLAY 0.808511 (-2240 1785);
FORCEPROP 2 LASTPIN (-2400 1775) $PN 2
J 2
(-2410 1785);
DISPLAY 0.808511 (-2410 1785);
FORCEPROP 2 LAST VALUE DIFF BUS_0.22UF
J 2
(-2475 1775);
DISPLAY 0.553191 (-2475 1775);
FORCEPROP 2 LAST TOLERANCE 20%
J 2
(-2400 1825);
DISPLAY 0.553191 (-2400 1825);
DISPLAY INVISIBLE (-2400 1825);
FORCEPROP 2 LAST PACK_TYPE C0201
J 2
(-2500 1825);
DISPLAY 0.553191 (-2500 1825);
DISPLAY INVISIBLE (-2500 1825);
FORCEPROP 1 LAST MATERIAL X6S
J 2
(-2316 1854);
DISPLAY 0.574468 (-2316 1854);
PAINT GREEN (-2316 1854);
DISPLAY INVISIBLE (-2316 1854);
FORCEPROP 2 LAST VOLTAGE 6.3V
J 2
(-2675 1825);
DISPLAY 0.553191 (-2675 1825);
DISPLAY INVISIBLE (-2675 1825);
FORCEPROP 1 LAST PIN_NAMES_ROTATE TRUE
J 2
(-2325 1775);
DISPLAY 0.489362 (-2325 1775);
PAINT GREEN (-2325 1775);
DISPLAY INVISIBLE (-2325 1775);
FORCEPROP 2 LAST CDS_LIB pure_quanta
J 2
(-2325 1775);
DISPLAY INVISIBLE (-2325 1775);
FORCEPROP 1 LAST CDS_LMAN_SYM_OUTLINE -25,50,25,-50
J 2
(-2325 1775);
DISPLAY 0.468085 (-2325 1775);
PAINT GREEN (-2325 1775);
DISPLAY INVISIBLE (-2325 1775);
FORCEPROP 1 LAST PATH I30
J 2
(-2325 1775);
DISPLAY 0.723404 (-2325 1775);
DISPLAY INVISIBLE (-2325 1775);
FORCEPROP 1 LAST PART_NUMBER SP_CH4221MEE01
J 2
(-2441 1863);
DISPLAY 0.574468 (-2441 1863);
PAINT GREEN (-2441 1863);
DISPLAY INVISIBLE (-2441 1863);
FORCEPROP 1 LAST LOCATION C6697
J 0
(-2075 1850);
DISPLAY 1.021277 (-2075 1850);
DISPLAY INVISIBLE (-2075 1850);
FORCEADD TAP..1
R 2
(-3300 2125);
FORCEPROP 3 LASTPIN (-3250 2125) SIG_NAME P5E_CPU1_P2_TX_BUF_DN<0>
J 0
(-3240 2135);
DISPLAY 0.659574 (-3240 2135);
PAINT MONO (-3240 2135);
DISPLAY INVISIBLE (-3240 2135);
FORCEPROP 1 LASTPIN (-3250 2125) BN 0
J 2
(-3238 2133);
DISPLAY 0.680851 (-3238 2133);
PAINT GREEN (-3238 2133);
FORCEPROP 2 LAST CDS_LIB standard
J 0
(-3300 2125);
DISPLAY INVISIBLE (-3300 2125);
FORCEPROP 1 LAST BODY_TYPE PLUMBING
J 2
(-3300 2175);
DISPLAY 0.872340 (-3300 2175);
PAINT GREEN (-3300 2175);
DISPLAY INVISIBLE (-3300 2175);
FORCEPROP 1 LAST HDL_TAP TRUE
J 2
(-3625 2000);
DISPLAY 0.872340 (-3625 2000);
DISPLAY INVISIBLE (-3625 2000);
FORCEPROP 1 LAST PATH I31
J 2
(-3298 2125);
DISPLAY 0.872340 (-3298 2125);
PAINT GREEN (-3298 2125);
DISPLAY INVISIBLE (-3298 2125);
FORCEADD TAP..1
R 2
(-3050 2175);
FORCEPROP 3 LASTPIN (-3000 2175) SIG_NAME P5E_CPU1_P2_TX_BUF_DP<0>
J 0
(-2990 2185);
DISPLAY 0.659574 (-2990 2185);
PAINT MONO (-2990 2185);
DISPLAY INVISIBLE (-2990 2185);
FORCEPROP 1 LASTPIN (-3000 2175) BN 0
J 2
(-2988 2183);
DISPLAY 0.680851 (-2988 2183);
PAINT GREEN (-2988 2183);
FORCEPROP 2 LAST CDS_LIB standard
J 0
(-3050 2175);
DISPLAY INVISIBLE (-3050 2175);
FORCEPROP 1 LAST BODY_TYPE PLUMBING
J 2
(-3050 2225);
DISPLAY 0.872340 (-3050 2225);
PAINT GREEN (-3050 2225);
DISPLAY INVISIBLE (-3050 2225);
FORCEPROP 1 LAST HDL_TAP TRUE
J 2
(-3375 2050);
DISPLAY 0.872340 (-3375 2050);
DISPLAY INVISIBLE (-3375 2050);
FORCEPROP 1 LAST PATH I32
J 2
(-3048 2175);
DISPLAY 0.872340 (-3048 2175);
PAINT GREEN (-3048 2175);
DISPLAY INVISIBLE (-3048 2175);
FORCEADD PT5161LRS..10
(-7775 4625);
FORCEPROP 1 LAST LOCATION U6016
J 0
(-8125 6250);
DISPLAY 0.723404 (-8125 6250);
PAINT GREEN (-8125 6250);
FORCEPROP 0 LAST $SEC 10
J 0
(-8125 6400);
DISPLAY 0.680851 (-8125 6400);
PAINT MONO (-8125 6400);
DISPLAY INVISIBLE (-8125 6400);
FORCEPROP 0 LAST CDS_SEC 10
J 0
(-8125 6400);
DISPLAY 0.680851 (-8125 6400);
DISPLAY INVISIBLE (-8125 6400);
FORCEPROP 0 LASTPIN (-7325 5775) $PN P10
J 0
(-7315 5785);
DISPLAY 0.680851 (-7315 5785);
PAINT MONO (-7315 5785);
FORCEPROP 0 LASTPIN (-7325 5425) $PN AA10
J 0
(-7315 5435);
DISPLAY 0.680851 (-7315 5435);
PAINT MONO (-7315 5435);
FORCEPROP 0 LASTPIN (-7325 5075) $PN AH10
J 0
(-7315 5085);
DISPLAY 0.680851 (-7315 5085);
PAINT MONO (-7315 5085);
FORCEPROP 0 LASTPIN (-7325 4725) $PN AR10
J 0
(-7315 4735);
DISPLAY 0.680851 (-7315 4735);
PAINT MONO (-7315 4735);
FORCEPROP 0 LASTPIN (-7325 4375) $PN BB10
J 0
(-7315 4385);
DISPLAY 0.680851 (-7315 4385);
PAINT MONO (-7315 4385);
FORCEPROP 0 LASTPIN (-7325 4025) $PN BJ10
J 0
(-7315 4035);
DISPLAY 0.680851 (-7315 4035);
PAINT MONO (-7315 4035);
FORCEPROP 0 LASTPIN (-7325 3675) $PN BT10
J 0
(-7315 3685);
DISPLAY 0.680851 (-7315 3685);
PAINT MONO (-7315 3685);
FORCEPROP 0 LASTPIN (-7325 3325) $PN CC10
J 0
(-7315 3335);
DISPLAY 0.680851 (-7315 3335);
PAINT MONO (-7315 3335);
FORCEPROP 0 LASTPIN (-7325 5875) $PN M7
J 0
(-7315 5885);
DISPLAY 0.680851 (-7315 5885);
PAINT MONO (-7315 5885);
FORCEPROP 0 LASTPIN (-7325 5525) $PN W7
J 0
(-7315 5535);
DISPLAY 0.680851 (-7315 5535);
PAINT MONO (-7315 5535);
FORCEPROP 0 LASTPIN (-7325 5175) $PN AF7
J 0
(-7315 5185);
DISPLAY 0.680851 (-7315 5185);
PAINT MONO (-7315 5185);
FORCEPROP 0 LASTPIN (-7325 4825) $PN AN7
J 0
(-7315 4835);
DISPLAY 0.680851 (-7315 4835);
PAINT MONO (-7315 4835);
FORCEPROP 0 LASTPIN (-7325 4475) $PN AY7
J 0
(-7315 4485);
DISPLAY 0.680851 (-7315 4485);
PAINT MONO (-7315 4485);
FORCEPROP 0 LASTPIN (-7325 4125) $PN BG7
J 0
(-7315 4135);
DISPLAY 0.680851 (-7315 4135);
PAINT MONO (-7315 4135);
FORCEPROP 0 LASTPIN (-7325 3775) $PN BP7
J 0
(-7315 3785);
DISPLAY 0.680851 (-7315 3785);
PAINT MONO (-7315 3785);
FORCEPROP 0 LASTPIN (-7325 3425) $PN CA7
J 0
(-7315 3435);
DISPLAY 0.680851 (-7315 3435);
PAINT MONO (-7315 3435);
FORCEPROP 2 LAST VALUE PT5161LRS
J 0
(-8125 6300);
DISPLAY 0.680851 (-8125 6300);
FORCEPROP 1 LAST MATERIAL IC
J 0
(-8125 6100);
DISPLAY 0.723404 (-8125 6100);
PAINT GREEN (-8125 6100);
FORCEPROP 2 LAST PART_TYPE SMLF
J 0
(-8125 6350);
DISPLAY 0.680851 (-8125 6350);
FORCEPROP 2 LAST CDS_LIB pure_quanta
J 0
(-7775 4625);
DISPLAY INVISIBLE (-7775 4625);
FORCEPROP 1 LAST CDS_LMAN_SYM_OUTLINE -350,1450,300,-1400
J 0
(-7775 4625);
DISPLAY 0.468085 (-7775 4625);
PAINT GREEN (-7775 4625);
DISPLAY INVISIBLE (-7775 4625);
FORCEPROP 1 LAST NEEDS_NO_SIZE TRUE
J 0
(-7775 4625);
DISPLAY 0.723404 (-7775 4625);
PAINT GREEN (-7775 4625);
DISPLAY INVISIBLE (-7775 4625);
FORCEPROP 1 LAST PATH I33
J 0
(-7775 4625);
DISPLAY 0.723404 (-7775 4625);
PAINT GREEN (-7775 4625);
DISPLAY INVISIBLE (-7775 4625);
FORCEPROP 1 LAST PART_NUMBER AJ051610U03
J 0
(-8125 6175);
DISPLAY 0.723404 (-8125 6175);
PAINT GREEN (-8125 6175);
DISPLAY INVISIBLE (-8125 6175);
FORCEADD Q_CAP_DIFFBUS..2
R 2
(-2325 2175);
FORCEPROP 1 LAST LOCATION C6693
J 2
(-2025 2175);
DISPLAY 0.723404 (-2025 2175);
PAINT GREEN (-2025 2175);
FORCEPROP 2 LAST $SEC 1
J 2
(-2150 2250);
DISPLAY 0.680851 (-2150 2250);
PAINT MONO (-2150 2250);
DISPLAY INVISIBLE (-2150 2250);
FORCEPROP 2 LAST CDS_SEC 1
J 2
(-2150 2250);
DISPLAY 0.680851 (-2150 2250);
DISPLAY INVISIBLE (-2150 2250);
FORCEPROP 2 LASTPIN (-2250 2175) $PN 1
J 0
(-2240 2185);
DISPLAY 0.808511 (-2240 2185);
FORCEPROP 2 LASTPIN (-2400 2175) $PN 2
J 2
(-2410 2185);
DISPLAY 0.808511 (-2410 2185);
FORCEPROP 2 LAST VOLTAGE 6.3V
J 2
(-2150 2325);
DISPLAY 0.553191 (-2150 2325);
PAINT GREEN (-2150 2325);
FORCEPROP 2 LAST TOLERANCE 20%
J 2
(-2275 2325);
DISPLAY 0.553191 (-2275 2325);
PAINT GREEN (-2275 2325);
FORCEPROP 2 LAST VALUE DIFF BUS_0.22UF
J 2
(-2475 2175);
DISPLAY 0.553191 (-2475 2175);
FORCEPROP 1 LAST MATERIAL X6S
J 2
(-2416 2379);
DISPLAY 0.574468 (-2416 2379);
PAINT GREEN (-2416 2379);
FORCEPROP 2 LAST PACK_TYPE C0201
J 2
(-2375 2325);
DISPLAY 0.553191 (-2375 2325);
PAINT GREEN (-2375 2325);
FORCEPROP 1 LAST PIN_NAMES_ROTATE TRUE
J 2
(-2325 2175);
DISPLAY 0.489362 (-2325 2175);
PAINT GREEN (-2325 2175);
DISPLAY INVISIBLE (-2325 2175);
FORCEPROP 1 LAST CDS_LMAN_SYM_OUTLINE -25,50,25,-50
J 2
(-2325 2175);
DISPLAY 0.468085 (-2325 2175);
PAINT GREEN (-2325 2175);
DISPLAY INVISIBLE (-2325 2175);
FORCEPROP 2 LAST CDS_LIB pure_quanta
J 2
(-2325 2175);
DISPLAY INVISIBLE (-2325 2175);
FORCEPROP 1 LAST PATH I34
J 2
(-2325 2175);
DISPLAY 0.723404 (-2325 2175);
DISPLAY INVISIBLE (-2325 2175);
FORCEPROP 1 LAST PART_NUMBER SP_CH4221MEE01
J 2
(-2141 2263);
DISPLAY 0.574468 (-2141 2263);
PAINT GREEN (-2141 2263);
DISPLAY INVISIBLE (-2141 2263);
FORCEPROP 1 LAST LOCATION C6693
J 0
(-2075 2250);
DISPLAY 1.021277 (-2075 2250);
DISPLAY INVISIBLE (-2075 2250);
FORCEADD Q_CAP_DIFFBUS..2
R 2
(-2325 2125);
FORCEPROP 1 LAST LOCATION C6694
J 2
(-2025 2125);
DISPLAY 0.723404 (-2025 2125);
PAINT GREEN (-2025 2125);
FORCEPROP 2 LAST $SEC 1
J 2
(-2150 2200);
DISPLAY 0.680851 (-2150 2200);
PAINT MONO (-2150 2200);
DISPLAY INVISIBLE (-2150 2200);
FORCEPROP 2 LAST CDS_SEC 1
J 2
(-2150 2200);
DISPLAY 0.680851 (-2150 2200);
DISPLAY INVISIBLE (-2150 2200);
FORCEPROP 2 LASTPIN (-2250 2125) $PN 1
J 0
(-2240 2135);
DISPLAY 0.808511 (-2240 2135);
FORCEPROP 2 LASTPIN (-2400 2125) $PN 2
J 2
(-2410 2135);
DISPLAY 0.808511 (-2410 2135);
FORCEPROP 2 LAST VALUE DIFF BUS_0.22UF
J 2
(-2475 2125);
DISPLAY 0.553191 (-2475 2125);
FORCEPROP 2 LAST TOLERANCE 20%
J 2
(-2400 2175);
DISPLAY 0.553191 (-2400 2175);
DISPLAY INVISIBLE (-2400 2175);
FORCEPROP 2 LAST PACK_TYPE C0201
J 2
(-2500 2175);
DISPLAY 0.553191 (-2500 2175);
DISPLAY INVISIBLE (-2500 2175);
FORCEPROP 1 LAST MATERIAL X6S
J 2
(-2316 2204);
DISPLAY 0.574468 (-2316 2204);
PAINT GREEN (-2316 2204);
DISPLAY INVISIBLE (-2316 2204);
FORCEPROP 2 LAST VOLTAGE 6.3V
J 2
(-2675 2175);
DISPLAY 0.553191 (-2675 2175);
DISPLAY INVISIBLE (-2675 2175);
FORCEPROP 1 LAST PIN_NAMES_ROTATE TRUE
J 2
(-2325 2125);
DISPLAY 0.489362 (-2325 2125);
PAINT GREEN (-2325 2125);
DISPLAY INVISIBLE (-2325 2125);
FORCEPROP 2 LAST CDS_LIB pure_quanta
J 2
(-2325 2125);
DISPLAY INVISIBLE (-2325 2125);
FORCEPROP 1 LAST CDS_LMAN_SYM_OUTLINE -25,50,25,-50
J 2
(-2325 2125);
DISPLAY 0.468085 (-2325 2125);
PAINT GREEN (-2325 2125);
DISPLAY INVISIBLE (-2325 2125);
FORCEPROP 1 LAST PATH I35
J 2
(-2325 2125);
DISPLAY 0.723404 (-2325 2125);
DISPLAY INVISIBLE (-2325 2125);
FORCEPROP 1 LAST PART_NUMBER SP_CH4221MEE01
J 2
(-2441 2213);
DISPLAY 0.574468 (-2441 2213);
PAINT GREEN (-2441 2213);
DISPLAY INVISIBLE (-2441 2213);
FORCEPROP 1 LAST LOCATION C6694
J 0
(-2075 2200);
DISPLAY 1.021277 (-2075 2200);
DISPLAY INVISIBLE (-2075 2200);
FORCEADD TAP..1
(-7050 3425);
FORCEPROP 3 LASTPIN (-7100 3425) SIG_NAME P5E_CPU1_P2_TX_BUF_DP<8>
J 0
(-7090 3435);
DISPLAY 0.659574 (-7090 3435);
PAINT MONO (-7090 3435);
DISPLAY INVISIBLE (-7090 3435);
FORCEPROP 1 LASTPIN (-7100 3425) BN 8
J 0
(-7112 3433);
DISPLAY 0.680851 (-7112 3433);
PAINT GREEN (-7112 3433);
FORCEPROP 2 LAST CDS_LIB standard
J 0
(-7050 3425);
DISPLAY INVISIBLE (-7050 3425);
FORCEPROP 1 LAST BODY_TYPE PLUMBING
J 0
(-7050 3475);
DISPLAY 0.872340 (-7050 3475);
PAINT GREEN (-7050 3475);
DISPLAY INVISIBLE (-7050 3475);
FORCEPROP 1 LAST HDL_TAP TRUE
J 0
(-6725 3300);
DISPLAY 0.872340 (-6725 3300);
DISPLAY INVISIBLE (-6725 3300);
FORCEPROP 1 LAST PATH I36
J 0
(-7052 3425);
DISPLAY 0.872340 (-7052 3425);
PAINT GREEN (-7052 3425);
DISPLAY INVISIBLE (-7052 3425);
FORCEADD TAP..1
(-7050 3775);
FORCEPROP 3 LASTPIN (-7100 3775) SIG_NAME P5E_CPU1_P2_TX_BUF_DP<9>
J 0
(-7090 3785);
DISPLAY 0.659574 (-7090 3785);
PAINT MONO (-7090 3785);
DISPLAY INVISIBLE (-7090 3785);
FORCEPROP 1 LASTPIN (-7100 3775) BN 9
J 0
(-7112 3783);
DISPLAY 0.680851 (-7112 3783);
PAINT GREEN (-7112 3783);
FORCEPROP 2 LAST CDS_LIB standard
J 0
(-7050 3775);
DISPLAY INVISIBLE (-7050 3775);
FORCEPROP 1 LAST BODY_TYPE PLUMBING
J 0
(-7050 3825);
DISPLAY 0.872340 (-7050 3825);
PAINT GREEN (-7050 3825);
DISPLAY INVISIBLE (-7050 3825);
FORCEPROP 1 LAST HDL_TAP TRUE
J 0
(-6725 3650);
DISPLAY 0.872340 (-6725 3650);
DISPLAY INVISIBLE (-6725 3650);
FORCEPROP 1 LAST PATH I37
J 0
(-7052 3775);
DISPLAY 0.872340 (-7052 3775);
PAINT GREEN (-7052 3775);
DISPLAY INVISIBLE (-7052 3775);
FORCEADD TAP..1
(-7050 4125);
FORCEPROP 3 LASTPIN (-7100 4125) SIG_NAME P5E_CPU1_P2_TX_BUF_DP<10>
J 0
(-7090 4135);
DISPLAY 0.659574 (-7090 4135);
PAINT MONO (-7090 4135);
DISPLAY INVISIBLE (-7090 4135);
FORCEPROP 1 LASTPIN (-7100 4125) BN 10
J 0
(-7112 4133);
DISPLAY 0.680851 (-7112 4133);
PAINT GREEN (-7112 4133);
FORCEPROP 2 LAST CDS_LIB standard
J 0
(-7050 4125);
DISPLAY INVISIBLE (-7050 4125);
FORCEPROP 1 LAST BODY_TYPE PLUMBING
J 0
(-7050 4175);
DISPLAY 0.872340 (-7050 4175);
PAINT GREEN (-7050 4175);
DISPLAY INVISIBLE (-7050 4175);
FORCEPROP 1 LAST HDL_TAP TRUE
J 0
(-6725 4000);
DISPLAY 0.872340 (-6725 4000);
DISPLAY INVISIBLE (-6725 4000);
FORCEPROP 1 LAST PATH I38
J 0
(-7052 4125);
DISPLAY 0.872340 (-7052 4125);
PAINT GREEN (-7052 4125);
DISPLAY INVISIBLE (-7052 4125);
FORCEADD TAP..1
(-6850 3325);
FORCEPROP 3 LASTPIN (-6900 3325) SIG_NAME P5E_CPU1_P2_TX_BUF_DN<8>
J 0
(-6890 3335);
DISPLAY 0.659574 (-6890 3335);
PAINT MONO (-6890 3335);
DISPLAY INVISIBLE (-6890 3335);
FORCEPROP 1 LASTPIN (-6900 3325) BN 8
J 0
(-6912 3333);
DISPLAY 0.680851 (-6912 3333);
PAINT GREEN (-6912 3333);
FORCEPROP 2 LAST CDS_LIB standard
J 0
(-6850 3325);
DISPLAY INVISIBLE (-6850 3325);
FORCEPROP 1 LAST BODY_TYPE PLUMBING
J 0
(-6850 3375);
DISPLAY 0.872340 (-6850 3375);
PAINT GREEN (-6850 3375);
DISPLAY INVISIBLE (-6850 3375);
FORCEPROP 1 LAST HDL_TAP TRUE
J 0
(-6525 3200);
DISPLAY 0.872340 (-6525 3200);
DISPLAY INVISIBLE (-6525 3200);
FORCEPROP 1 LAST PATH I39
J 0
(-6852 3325);
DISPLAY 0.872340 (-6852 3325);
PAINT GREEN (-6852 3325);
DISPLAY INVISIBLE (-6852 3325);
FORCEADD TAP..1
R 2
(-3300 925);
FORCEPROP 3 LASTPIN (-3250 925) SIG_NAME P5E_CPU1_P2_TX_BUF_DN<6>
J 0
(-3240 935);
DISPLAY 0.659574 (-3240 935);
PAINT MONO (-3240 935);
DISPLAY INVISIBLE (-3240 935);
FORCEPROP 1 LASTPIN (-3250 925) BN 6
J 2
(-3238 933);
DISPLAY 0.680851 (-3238 933);
PAINT GREEN (-3238 933);
FORCEPROP 2 LAST CDS_LIB standard
J 0
(-3300 925);
DISPLAY INVISIBLE (-3300 925);
FORCEPROP 1 LAST BODY_TYPE PLUMBING
J 2
(-3300 975);
DISPLAY 0.872340 (-3300 975);
PAINT GREEN (-3300 975);
DISPLAY INVISIBLE (-3300 975);
FORCEPROP 1 LAST HDL_TAP TRUE
J 2
(-3625 800);
DISPLAY 0.872340 (-3625 800);
DISPLAY INVISIBLE (-3625 800);
FORCEPROP 1 LAST PATH I4
J 2
(-3298 925);
DISPLAY 0.872340 (-3298 925);
PAINT GREEN (-3298 925);
DISPLAY INVISIBLE (-3298 925);
FORCEADD TAP..1
(-6850 3675);
FORCEPROP 3 LASTPIN (-6900 3675) SIG_NAME P5E_CPU1_P2_TX_BUF_DN<9>
J 0
(-6890 3685);
DISPLAY 0.659574 (-6890 3685);
PAINT MONO (-6890 3685);
DISPLAY INVISIBLE (-6890 3685);
FORCEPROP 1 LASTPIN (-6900 3675) BN 9
J 0
(-6912 3683);
DISPLAY 0.680851 (-6912 3683);
PAINT GREEN (-6912 3683);
FORCEPROP 2 LAST CDS_LIB standard
J 0
(-6850 3675);
DISPLAY INVISIBLE (-6850 3675);
FORCEPROP 1 LAST BODY_TYPE PLUMBING
J 0
(-6850 3725);
DISPLAY 0.872340 (-6850 3725);
PAINT GREEN (-6850 3725);
DISPLAY INVISIBLE (-6850 3725);
FORCEPROP 1 LAST HDL_TAP TRUE
J 0
(-6525 3550);
DISPLAY 0.872340 (-6525 3550);
DISPLAY INVISIBLE (-6525 3550);
FORCEPROP 1 LAST PATH I40
J 0
(-6852 3675);
DISPLAY 0.872340 (-6852 3675);
PAINT GREEN (-6852 3675);
DISPLAY INVISIBLE (-6852 3675);
FORCEADD TAP..1
(-6850 4025);
FORCEPROP 3 LASTPIN (-6900 4025) SIG_NAME P5E_CPU1_P2_TX_BUF_DN<10>
J 0
(-6890 4035);
DISPLAY 0.659574 (-6890 4035);
PAINT MONO (-6890 4035);
DISPLAY INVISIBLE (-6890 4035);
FORCEPROP 1 LASTPIN (-6900 4025) BN 10
J 0
(-6912 4033);
DISPLAY 0.680851 (-6912 4033);
PAINT GREEN (-6912 4033);
FORCEPROP 2 LAST CDS_LIB standard
J 0
(-6850 4025);
DISPLAY INVISIBLE (-6850 4025);
FORCEPROP 1 LAST BODY_TYPE PLUMBING
J 0
(-6850 4075);
DISPLAY 0.872340 (-6850 4075);
PAINT GREEN (-6850 4075);
DISPLAY INVISIBLE (-6850 4075);
FORCEPROP 1 LAST HDL_TAP TRUE
J 0
(-6525 3900);
DISPLAY 0.872340 (-6525 3900);
DISPLAY INVISIBLE (-6525 3900);
FORCEPROP 1 LAST PATH I41
J 0
(-6852 4025);
DISPLAY 0.872340 (-6852 4025);
PAINT GREEN (-6852 4025);
DISPLAY INVISIBLE (-6852 4025);
FORCEADD TAP..1
(-1575 725);
FORCEPROP 3 LASTPIN (-1625 725) SIG_NAME P5E_CPU1_P2_TX_BUF_C_DN<7>
J 0
(-1615 735);
DISPLAY 0.659574 (-1615 735);
PAINT MONO (-1615 735);
DISPLAY INVISIBLE (-1615 735);
FORCEPROP 1 LASTPIN (-1625 725) BN 7
J 0
(-1637 733);
DISPLAY 0.680851 (-1637 733);
PAINT GREEN (-1637 733);
FORCEPROP 2 LAST CDS_LIB standard
J 0
(-1575 725);
DISPLAY INVISIBLE (-1575 725);
FORCEPROP 1 LAST BODY_TYPE PLUMBING
J 0
(-1575 775);
DISPLAY 0.872340 (-1575 775);
PAINT GREEN (-1575 775);
DISPLAY INVISIBLE (-1575 775);
FORCEPROP 1 LAST HDL_TAP TRUE
J 0
(-1250 600);
DISPLAY 0.872340 (-1250 600);
DISPLAY INVISIBLE (-1250 600);
FORCEPROP 1 LAST PATH I42
J 0
(-1577 725);
DISPLAY 0.872340 (-1577 725);
PAINT GREEN (-1577 725);
DISPLAY INVISIBLE (-1577 725);
FORCEADD TAP..1
(-1775 775);
FORCEPROP 3 LASTPIN (-1825 775) SIG_NAME P5E_CPU1_P2_TX_BUF_C_DP<7>
J 0
(-1815 785);
DISPLAY 0.659574 (-1815 785);
PAINT MONO (-1815 785);
DISPLAY INVISIBLE (-1815 785);
FORCEPROP 1 LASTPIN (-1825 775) BN 7
J 0
(-1837 783);
DISPLAY 0.680851 (-1837 783);
PAINT GREEN (-1837 783);
FORCEPROP 2 LAST CDS_LIB standard
J 0
(-1775 775);
DISPLAY INVISIBLE (-1775 775);
FORCEPROP 1 LAST BODY_TYPE PLUMBING
J 0
(-1775 825);
DISPLAY 0.872340 (-1775 825);
PAINT GREEN (-1775 825);
DISPLAY INVISIBLE (-1775 825);
FORCEPROP 1 LAST HDL_TAP TRUE
J 0
(-1450 650);
DISPLAY 0.872340 (-1450 650);
DISPLAY INVISIBLE (-1450 650);
FORCEPROP 1 LAST PATH I43
J 0
(-1777 775);
DISPLAY 0.872340 (-1777 775);
PAINT GREEN (-1777 775);
DISPLAY INVISIBLE (-1777 775);
FORCEADD TAP..1
(-1775 975);
FORCEPROP 3 LASTPIN (-1825 975) SIG_NAME P5E_CPU1_P2_TX_BUF_C_DP<6>
J 0
(-1815 985);
DISPLAY 0.659574 (-1815 985);
PAINT MONO (-1815 985);
DISPLAY INVISIBLE (-1815 985);
FORCEPROP 1 LASTPIN (-1825 975) BN 6
J 0
(-1837 983);
DISPLAY 0.680851 (-1837 983);
PAINT GREEN (-1837 983);
FORCEPROP 2 LAST CDS_LIB standard
J 0
(-1775 975);
DISPLAY INVISIBLE (-1775 975);
FORCEPROP 1 LAST BODY_TYPE PLUMBING
J 0
(-1775 1025);
DISPLAY 0.872340 (-1775 1025);
PAINT GREEN (-1775 1025);
DISPLAY INVISIBLE (-1775 1025);
FORCEPROP 1 LAST HDL_TAP TRUE
J 0
(-1450 850);
DISPLAY 0.872340 (-1450 850);
DISPLAY INVISIBLE (-1450 850);
FORCEPROP 1 LAST PATH I44
J 0
(-1777 975);
DISPLAY 0.872340 (-1777 975);
PAINT GREEN (-1777 975);
DISPLAY INVISIBLE (-1777 975);
FORCEADD TAP..1
(-1575 925);
FORCEPROP 3 LASTPIN (-1625 925) SIG_NAME P5E_CPU1_P2_TX_BUF_C_DN<6>
J 0
(-1615 935);
DISPLAY 0.659574 (-1615 935);
PAINT MONO (-1615 935);
DISPLAY INVISIBLE (-1615 935);
FORCEPROP 1 LASTPIN (-1625 925) BN 6
J 0
(-1637 933);
DISPLAY 0.680851 (-1637 933);
PAINT GREEN (-1637 933);
FORCEPROP 2 LAST CDS_LIB standard
J 0
(-1575 925);
DISPLAY INVISIBLE (-1575 925);
FORCEPROP 1 LAST BODY_TYPE PLUMBING
J 0
(-1575 975);
DISPLAY 0.872340 (-1575 975);
PAINT GREEN (-1575 975);
DISPLAY INVISIBLE (-1575 975);
FORCEPROP 1 LAST HDL_TAP TRUE
J 0
(-1250 800);
DISPLAY 0.872340 (-1250 800);
DISPLAY INVISIBLE (-1250 800);
FORCEPROP 1 LAST PATH I45
J 0
(-1577 925);
DISPLAY 0.872340 (-1577 925);
PAINT GREEN (-1577 925);
DISPLAY INVISIBLE (-1577 925);
FORCEADD TAP..1
(-1775 1175);
FORCEPROP 3 LASTPIN (-1825 1175) SIG_NAME P5E_CPU1_P2_TX_BUF_C_DP<5>
J 0
(-1815 1185);
DISPLAY 0.659574 (-1815 1185);
PAINT MONO (-1815 1185);
DISPLAY INVISIBLE (-1815 1185);
FORCEPROP 1 LASTPIN (-1825 1175) BN 5
J 0
(-1837 1183);
DISPLAY 0.680851 (-1837 1183);
PAINT GREEN (-1837 1183);
FORCEPROP 2 LAST CDS_LIB standard
J 0
(-1775 1175);
DISPLAY INVISIBLE (-1775 1175);
FORCEPROP 1 LAST BODY_TYPE PLUMBING
J 0
(-1775 1225);
DISPLAY 0.872340 (-1775 1225);
PAINT GREEN (-1775 1225);
DISPLAY INVISIBLE (-1775 1225);
FORCEPROP 1 LAST HDL_TAP TRUE
J 0
(-1450 1050);
DISPLAY 0.872340 (-1450 1050);
DISPLAY INVISIBLE (-1450 1050);
FORCEPROP 1 LAST PATH I46
J 0
(-1777 1175);
DISPLAY 0.872340 (-1777 1175);
PAINT GREEN (-1777 1175);
DISPLAY INVISIBLE (-1777 1175);
FORCEADD TAP..1
(-1575 1125);
FORCEPROP 3 LASTPIN (-1625 1125) SIG_NAME P5E_CPU1_P2_TX_BUF_C_DN<5>
J 0
(-1615 1135);
DISPLAY 0.659574 (-1615 1135);
PAINT MONO (-1615 1135);
DISPLAY INVISIBLE (-1615 1135);
FORCEPROP 1 LASTPIN (-1625 1125) BN 5
J 0
(-1637 1133);
DISPLAY 0.680851 (-1637 1133);
PAINT GREEN (-1637 1133);
FORCEPROP 2 LAST CDS_LIB standard
J 0
(-1575 1125);
DISPLAY INVISIBLE (-1575 1125);
FORCEPROP 1 LAST BODY_TYPE PLUMBING
J 0
(-1575 1175);
DISPLAY 0.872340 (-1575 1175);
PAINT GREEN (-1575 1175);
DISPLAY INVISIBLE (-1575 1175);
FORCEPROP 1 LAST HDL_TAP TRUE
J 0
(-1250 1000);
DISPLAY 0.872340 (-1250 1000);
DISPLAY INVISIBLE (-1250 1000);
FORCEPROP 1 LAST PATH I47
J 0
(-1577 1125);
DISPLAY 0.872340 (-1577 1125);
PAINT GREEN (-1577 1125);
DISPLAY INVISIBLE (-1577 1125);
FORCEADD TAP..1
(-1775 1375);
FORCEPROP 3 LASTPIN (-1825 1375) SIG_NAME P5E_CPU1_P2_TX_BUF_C_DP<4>
J 0
(-1815 1385);
DISPLAY 0.659574 (-1815 1385);
PAINT MONO (-1815 1385);
DISPLAY INVISIBLE (-1815 1385);
FORCEPROP 1 LASTPIN (-1825 1375) BN 4
J 0
(-1837 1383);
DISPLAY 0.680851 (-1837 1383);
PAINT GREEN (-1837 1383);
FORCEPROP 2 LAST CDS_LIB standard
J 0
(-1775 1375);
DISPLAY INVISIBLE (-1775 1375);
FORCEPROP 1 LAST BODY_TYPE PLUMBING
J 0
(-1775 1425);
DISPLAY 0.872340 (-1775 1425);
PAINT GREEN (-1775 1425);
DISPLAY INVISIBLE (-1775 1425);
FORCEPROP 1 LAST HDL_TAP TRUE
J 0
(-1450 1250);
DISPLAY 0.872340 (-1450 1250);
DISPLAY INVISIBLE (-1450 1250);
FORCEPROP 1 LAST PATH I48
J 0
(-1777 1375);
DISPLAY 0.872340 (-1777 1375);
PAINT GREEN (-1777 1375);
DISPLAY INVISIBLE (-1777 1375);
FORCEADD TAP..1
(-1575 1325);
FORCEPROP 3 LASTPIN (-1625 1325) SIG_NAME P5E_CPU1_P2_TX_BUF_C_DN<4>
J 0
(-1615 1335);
DISPLAY 0.659574 (-1615 1335);
PAINT MONO (-1615 1335);
DISPLAY INVISIBLE (-1615 1335);
FORCEPROP 1 LASTPIN (-1625 1325) BN 4
J 0
(-1637 1333);
DISPLAY 0.680851 (-1637 1333);
PAINT GREEN (-1637 1333);
FORCEPROP 2 LAST CDS_LIB standard
J 0
(-1575 1325);
DISPLAY INVISIBLE (-1575 1325);
FORCEPROP 1 LAST BODY_TYPE PLUMBING
J 0
(-1575 1375);
DISPLAY 0.872340 (-1575 1375);
PAINT GREEN (-1575 1375);
DISPLAY INVISIBLE (-1575 1375);
FORCEPROP 1 LAST HDL_TAP TRUE
J 0
(-1250 1200);
DISPLAY 0.872340 (-1250 1200);
DISPLAY INVISIBLE (-1250 1200);
FORCEPROP 1 LAST PATH I49
J 0
(-1577 1325);
DISPLAY 0.872340 (-1577 1325);
PAINT GREEN (-1577 1325);
DISPLAY INVISIBLE (-1577 1325);
FORCEADD TAP..1
R 2
(-3050 775);
FORCEPROP 3 LASTPIN (-3000 775) SIG_NAME P5E_CPU1_P2_TX_BUF_DP<7>
J 0
(-2990 785);
DISPLAY 0.659574 (-2990 785);
PAINT MONO (-2990 785);
DISPLAY INVISIBLE (-2990 785);
FORCEPROP 1 LASTPIN (-3000 775) BN 7
J 2
(-2988 783);
DISPLAY 0.680851 (-2988 783);
PAINT GREEN (-2988 783);
FORCEPROP 2 LAST CDS_LIB standard
J 0
(-3050 775);
DISPLAY INVISIBLE (-3050 775);
FORCEPROP 1 LAST BODY_TYPE PLUMBING
J 2
(-3050 825);
DISPLAY 0.872340 (-3050 825);
PAINT GREEN (-3050 825);
DISPLAY INVISIBLE (-3050 825);
FORCEPROP 1 LAST HDL_TAP TRUE
J 2
(-3375 650);
DISPLAY 0.872340 (-3375 650);
DISPLAY INVISIBLE (-3375 650);
FORCEPROP 1 LAST PATH I5
J 2
(-3048 775);
DISPLAY 0.872340 (-3048 775);
PAINT GREEN (-3048 775);
DISPLAY INVISIBLE (-3048 775);
FORCEADD TAP..1
(-1775 1575);
FORCEPROP 3 LASTPIN (-1825 1575) SIG_NAME P5E_CPU1_P2_TX_BUF_C_DP<3>
J 0
(-1815 1585);
DISPLAY 0.659574 (-1815 1585);
PAINT MONO (-1815 1585);
DISPLAY INVISIBLE (-1815 1585);
FORCEPROP 1 LASTPIN (-1825 1575) BN 3
J 0
(-1837 1583);
DISPLAY 0.680851 (-1837 1583);
PAINT GREEN (-1837 1583);
FORCEPROP 2 LAST CDS_LIB standard
J 0
(-1775 1575);
DISPLAY INVISIBLE (-1775 1575);
FORCEPROP 1 LAST BODY_TYPE PLUMBING
J 0
(-1775 1625);
DISPLAY 0.872340 (-1775 1625);
PAINT GREEN (-1775 1625);
DISPLAY INVISIBLE (-1775 1625);
FORCEPROP 1 LAST HDL_TAP TRUE
J 0
(-1450 1450);
DISPLAY 0.872340 (-1450 1450);
DISPLAY INVISIBLE (-1450 1450);
FORCEPROP 1 LAST PATH I50
J 0
(-1777 1575);
DISPLAY 0.872340 (-1777 1575);
PAINT GREEN (-1777 1575);
DISPLAY INVISIBLE (-1777 1575);
FORCEADD TAP..1
(-1575 1725);
FORCEPROP 3 LASTPIN (-1625 1725) SIG_NAME P5E_CPU1_P2_TX_BUF_C_DN<2>
J 0
(-1615 1735);
DISPLAY 0.659574 (-1615 1735);
PAINT MONO (-1615 1735);
DISPLAY INVISIBLE (-1615 1735);
FORCEPROP 1 LASTPIN (-1625 1725) BN 2
J 0
(-1637 1733);
DISPLAY 0.680851 (-1637 1733);
PAINT GREEN (-1637 1733);
FORCEPROP 2 LAST CDS_LIB standard
J 0
(-1575 1725);
DISPLAY INVISIBLE (-1575 1725);
FORCEPROP 1 LAST BODY_TYPE PLUMBING
J 0
(-1575 1775);
DISPLAY 0.872340 (-1575 1775);
PAINT GREEN (-1575 1775);
DISPLAY INVISIBLE (-1575 1775);
FORCEPROP 1 LAST HDL_TAP TRUE
J 0
(-1250 1600);
DISPLAY 0.872340 (-1250 1600);
DISPLAY INVISIBLE (-1250 1600);
FORCEPROP 1 LAST PATH I51
J 0
(-1577 1725);
DISPLAY 0.872340 (-1577 1725);
PAINT GREEN (-1577 1725);
DISPLAY INVISIBLE (-1577 1725);
FORCEADD TAP..1
(-1575 1525);
FORCEPROP 3 LASTPIN (-1625 1525) SIG_NAME P5E_CPU1_P2_TX_BUF_C_DN<3>
J 0
(-1615 1535);
DISPLAY 0.659574 (-1615 1535);
PAINT MONO (-1615 1535);
DISPLAY INVISIBLE (-1615 1535);
FORCEPROP 1 LASTPIN (-1625 1525) BN 3
J 0
(-1637 1533);
DISPLAY 0.680851 (-1637 1533);
PAINT GREEN (-1637 1533);
FORCEPROP 2 LAST CDS_LIB standard
J 0
(-1575 1525);
DISPLAY INVISIBLE (-1575 1525);
FORCEPROP 1 LAST BODY_TYPE PLUMBING
J 0
(-1575 1575);
DISPLAY 0.872340 (-1575 1575);
PAINT GREEN (-1575 1575);
DISPLAY INVISIBLE (-1575 1575);
FORCEPROP 1 LAST HDL_TAP TRUE
J 0
(-1250 1400);
DISPLAY 0.872340 (-1250 1400);
DISPLAY INVISIBLE (-1250 1400);
FORCEPROP 1 LAST PATH I52
J 0
(-1577 1525);
DISPLAY 0.872340 (-1577 1525);
PAINT GREEN (-1577 1525);
DISPLAY INVISIBLE (-1577 1525);
FORCEADD TAP..1
(-1775 1775);
FORCEPROP 3 LASTPIN (-1825 1775) SIG_NAME P5E_CPU1_P2_TX_BUF_C_DP<2>
J 0
(-1815 1785);
DISPLAY 0.659574 (-1815 1785);
PAINT MONO (-1815 1785);
DISPLAY INVISIBLE (-1815 1785);
FORCEPROP 1 LASTPIN (-1825 1775) BN 2
J 0
(-1837 1783);
DISPLAY 0.680851 (-1837 1783);
PAINT GREEN (-1837 1783);
FORCEPROP 2 LAST CDS_LIB standard
J 0
(-1775 1775);
DISPLAY INVISIBLE (-1775 1775);
FORCEPROP 1 LAST BODY_TYPE PLUMBING
J 0
(-1775 1825);
DISPLAY 0.872340 (-1775 1825);
PAINT GREEN (-1775 1825);
DISPLAY INVISIBLE (-1775 1825);
FORCEPROP 1 LAST HDL_TAP TRUE
J 0
(-1450 1650);
DISPLAY 0.872340 (-1450 1650);
DISPLAY INVISIBLE (-1450 1650);
FORCEPROP 1 LAST PATH I53
J 0
(-1777 1775);
DISPLAY 0.872340 (-1777 1775);
PAINT GREEN (-1777 1775);
DISPLAY INVISIBLE (-1777 1775);
FORCEADD TAP..1
(-1775 1975);
FORCEPROP 3 LASTPIN (-1825 1975) SIG_NAME P5E_CPU1_P2_TX_BUF_C_DP<1>
J 0
(-1815 1985);
DISPLAY 0.659574 (-1815 1985);
PAINT MONO (-1815 1985);
DISPLAY INVISIBLE (-1815 1985);
FORCEPROP 1 LASTPIN (-1825 1975) BN 1
J 0
(-1837 1983);
DISPLAY 0.680851 (-1837 1983);
PAINT GREEN (-1837 1983);
FORCEPROP 2 LAST CDS_LIB standard
J 0
(-1775 1975);
DISPLAY INVISIBLE (-1775 1975);
FORCEPROP 1 LAST BODY_TYPE PLUMBING
J 0
(-1775 2025);
DISPLAY 0.872340 (-1775 2025);
PAINT GREEN (-1775 2025);
DISPLAY INVISIBLE (-1775 2025);
FORCEPROP 1 LAST HDL_TAP TRUE
J 0
(-1450 1850);
DISPLAY 0.872340 (-1450 1850);
DISPLAY INVISIBLE (-1450 1850);
FORCEPROP 1 LAST PATH I54
J 0
(-1777 1975);
DISPLAY 0.872340 (-1777 1975);
PAINT GREEN (-1777 1975);
DISPLAY INVISIBLE (-1777 1975);
FORCEADD TAP..1
(-1575 1925);
FORCEPROP 3 LASTPIN (-1625 1925) SIG_NAME P5E_CPU1_P2_TX_BUF_C_DN<1>
J 0
(-1615 1935);
DISPLAY 0.659574 (-1615 1935);
PAINT MONO (-1615 1935);
DISPLAY INVISIBLE (-1615 1935);
FORCEPROP 1 LASTPIN (-1625 1925) BN 1
J 0
(-1637 1933);
DISPLAY 0.680851 (-1637 1933);
PAINT GREEN (-1637 1933);
FORCEPROP 2 LAST CDS_LIB standard
J 0
(-1575 1925);
DISPLAY INVISIBLE (-1575 1925);
FORCEPROP 1 LAST BODY_TYPE PLUMBING
J 0
(-1575 1975);
DISPLAY 0.872340 (-1575 1975);
PAINT GREEN (-1575 1975);
DISPLAY INVISIBLE (-1575 1975);
FORCEPROP 1 LAST HDL_TAP TRUE
J 0
(-1250 1800);
DISPLAY 0.872340 (-1250 1800);
DISPLAY INVISIBLE (-1250 1800);
FORCEPROP 1 LAST PATH I55
J 0
(-1577 1925);
DISPLAY 0.872340 (-1577 1925);
PAINT GREEN (-1577 1925);
DISPLAY INVISIBLE (-1577 1925);
FORCEADD TAP..1
(-1775 2175);
FORCEPROP 3 LASTPIN (-1825 2175) SIG_NAME P5E_CPU1_P2_TX_BUF_C_DP<0>
J 0
(-1815 2185);
DISPLAY 0.659574 (-1815 2185);
PAINT MONO (-1815 2185);
DISPLAY INVISIBLE (-1815 2185);
FORCEPROP 1 LASTPIN (-1825 2175) BN 0
J 0
(-1837 2183);
DISPLAY 0.680851 (-1837 2183);
PAINT GREEN (-1837 2183);
FORCEPROP 2 LAST CDS_LIB standard
J 0
(-1775 2175);
DISPLAY INVISIBLE (-1775 2175);
FORCEPROP 1 LAST BODY_TYPE PLUMBING
J 0
(-1775 2225);
DISPLAY 0.872340 (-1775 2225);
PAINT GREEN (-1775 2225);
DISPLAY INVISIBLE (-1775 2225);
FORCEPROP 1 LAST HDL_TAP TRUE
J 0
(-1450 2050);
DISPLAY 0.872340 (-1450 2050);
DISPLAY INVISIBLE (-1450 2050);
FORCEPROP 1 LAST PATH I56
J 0
(-1777 2175);
DISPLAY 0.872340 (-1777 2175);
PAINT GREEN (-1777 2175);
DISPLAY INVISIBLE (-1777 2175);
FORCEADD TAP..1
(-1575 2125);
FORCEPROP 3 LASTPIN (-1625 2125) SIG_NAME P5E_CPU1_P2_TX_BUF_C_DN<0>
J 0
(-1615 2135);
DISPLAY 0.659574 (-1615 2135);
PAINT MONO (-1615 2135);
DISPLAY INVISIBLE (-1615 2135);
FORCEPROP 1 LASTPIN (-1625 2125) BN 0
J 0
(-1637 2133);
DISPLAY 0.680851 (-1637 2133);
PAINT GREEN (-1637 2133);
FORCEPROP 2 LAST CDS_LIB standard
J 0
(-1575 2125);
DISPLAY INVISIBLE (-1575 2125);
FORCEPROP 1 LAST BODY_TYPE PLUMBING
J 0
(-1575 2175);
DISPLAY 0.872340 (-1575 2175);
PAINT GREEN (-1575 2175);
DISPLAY INVISIBLE (-1575 2175);
FORCEPROP 1 LAST HDL_TAP TRUE
J 0
(-1250 2000);
DISPLAY 0.872340 (-1250 2000);
DISPLAY INVISIBLE (-1250 2000);
FORCEPROP 1 LAST PATH I57
J 0
(-1577 2125);
DISPLAY 0.872340 (-1577 2125);
PAINT GREEN (-1577 2125);
DISPLAY INVISIBLE (-1577 2125);
FORCEADD OFFPAGE..2
(-575 2150);
FORCEPROP 2 LAST $XR0 120 
J 0
(-386 2150);
DISPLAY 0.638298 (-386 2150);
PAINT MONO (-386 2150);
FORCEPROP 2 LAST CDS_LIB standard
J 0
(-575 2150);
DISPLAY INVISIBLE (-575 2150);
FORCEPROP 1 LAST OFFPAGE TRUE
J 0
(-250 2025);
DISPLAY 0.872340 (-250 2025);
DISPLAY INVISIBLE (-250 2025);
FORCEPROP 1 LAST COMMENT_BODY TRUE
J 0
(-620 2055);
DISPLAY 0.872340 (-620 2055);
PAINT GREEN (-620 2055);
DISPLAY INVISIBLE (-620 2055);
FORCEPROP 2 LAST PATH I58
J 0
(-375 2200);
DISPLAY 0.680851 (-375 2200);
DISPLAY INVISIBLE (-375 2200);
FORCEADD OFFPAGE..2
(-575 2200);
FORCEPROP 2 LAST $XR0 120 
J 0
(-386 2200);
DISPLAY 0.638298 (-386 2200);
PAINT MONO (-386 2200);
FORCEPROP 2 LAST CDS_LIB standard
J 0
(-575 2200);
DISPLAY INVISIBLE (-575 2200);
FORCEPROP 1 LAST OFFPAGE TRUE
J 0
(-250 2075);
DISPLAY 0.872340 (-250 2075);
DISPLAY INVISIBLE (-250 2075);
FORCEPROP 1 LAST COMMENT_BODY TRUE
J 0
(-620 2105);
DISPLAY 0.872340 (-620 2105);
PAINT GREEN (-620 2105);
DISPLAY INVISIBLE (-620 2105);
FORCEPROP 2 LAST PATH I59
J 0
(-375 2250);
DISPLAY 0.680851 (-375 2250);
DISPLAY INVISIBLE (-375 2250);
FORCEADD TAP..1
R 2
(-3050 975);
FORCEPROP 3 LASTPIN (-3000 975) SIG_NAME P5E_CPU1_P2_TX_BUF_DP<6>
J 0
(-2990 985);
DISPLAY 0.659574 (-2990 985);
PAINT MONO (-2990 985);
DISPLAY INVISIBLE (-2990 985);
FORCEPROP 1 LASTPIN (-3000 975) BN 6
J 2
(-2988 983);
DISPLAY 0.680851 (-2988 983);
PAINT GREEN (-2988 983);
FORCEPROP 2 LAST CDS_LIB standard
J 0
(-3050 975);
DISPLAY INVISIBLE (-3050 975);
FORCEPROP 1 LAST BODY_TYPE PLUMBING
J 2
(-3050 1025);
DISPLAY 0.872340 (-3050 1025);
PAINT GREEN (-3050 1025);
DISPLAY INVISIBLE (-3050 1025);
FORCEPROP 1 LAST HDL_TAP TRUE
J 2
(-3375 850);
DISPLAY 0.872340 (-3375 850);
DISPLAY INVISIBLE (-3375 850);
FORCEPROP 1 LAST PATH I6
J 2
(-3048 975);
DISPLAY 0.872340 (-3048 975);
PAINT GREEN (-3048 975);
DISPLAY INVISIBLE (-3048 975);
FORCEADD OFFPAGE..1
(-9025 2275);
FORCEPROP 2 LAST $XR0 342 
J 0
(-9277 2275);
DISPLAY 0.638298 (-9277 2275);
PAINT MONO (-9277 2275);
FORCEPROP 2 LAST CDS_LIB standard
J 0
(-9025 2275);
DISPLAY INVISIBLE (-9025 2275);
FORCEPROP 1 LAST OFFPAGE TRUE
J 0
(-8700 2150);
DISPLAY 0.872340 (-8700 2150);
DISPLAY INVISIBLE (-8700 2150);
FORCEPROP 1 LAST COMMENT_BODY TRUE
J 0
(-8900 2175);
DISPLAY 0.872340 (-8900 2175);
PAINT GREEN (-8900 2175);
DISPLAY INVISIBLE (-8900 2175);
FORCEPROP 2 LAST PATH I60
J 0
(-9275 2325);
DISPLAY 0.680851 (-9275 2325);
DISPLAY INVISIBLE (-9275 2325);
FORCEADD OFFPAGE..1
(-9025 2225);
FORCEPROP 2 LAST $XR0 342 
J 0
(-9277 2225);
DISPLAY 0.638298 (-9277 2225);
PAINT MONO (-9277 2225);
FORCEPROP 2 LAST CDS_LIB standard
J 0
(-9025 2225);
DISPLAY INVISIBLE (-9025 2225);
FORCEPROP 1 LAST OFFPAGE TRUE
J 0
(-8700 2100);
DISPLAY 0.872340 (-8700 2100);
DISPLAY INVISIBLE (-8700 2100);
FORCEPROP 1 LAST COMMENT_BODY TRUE
J 0
(-8900 2125);
DISPLAY 0.872340 (-8900 2125);
PAINT GREEN (-8900 2125);
DISPLAY INVISIBLE (-8900 2125);
FORCEPROP 2 LAST PATH I61
J 0
(-9275 2275);
DISPLAY 0.680851 (-9275 2275);
DISPLAY INVISIBLE (-9275 2275);
FORCEADD TAP..1
(-7050 4475);
FORCEPROP 3 LASTPIN (-7100 4475) SIG_NAME P5E_CPU1_P2_TX_BUF_DP<11>
J 0
(-7090 4485);
DISPLAY 0.659574 (-7090 4485);
PAINT MONO (-7090 4485);
DISPLAY INVISIBLE (-7090 4485);
FORCEPROP 1 LASTPIN (-7100 4475) BN 11
J 0
(-7112 4483);
DISPLAY 0.680851 (-7112 4483);
PAINT GREEN (-7112 4483);
FORCEPROP 2 LAST CDS_LIB standard
J 0
(-7050 4475);
DISPLAY INVISIBLE (-7050 4475);
FORCEPROP 1 LAST BODY_TYPE PLUMBING
J 0
(-7050 4525);
DISPLAY 0.872340 (-7050 4525);
PAINT GREEN (-7050 4525);
DISPLAY INVISIBLE (-7050 4525);
FORCEPROP 1 LAST HDL_TAP TRUE
J 0
(-6725 4350);
DISPLAY 0.872340 (-6725 4350);
DISPLAY INVISIBLE (-6725 4350);
FORCEPROP 1 LAST PATH I62
J 0
(-7052 4475);
DISPLAY 0.872340 (-7052 4475);
PAINT GREEN (-7052 4475);
DISPLAY INVISIBLE (-7052 4475);
FORCEADD TAP..1
(-7050 4825);
FORCEPROP 3 LASTPIN (-7100 4825) SIG_NAME P5E_CPU1_P2_TX_BUF_DP<12>
J 0
(-7090 4835);
DISPLAY 0.659574 (-7090 4835);
PAINT MONO (-7090 4835);
DISPLAY INVISIBLE (-7090 4835);
FORCEPROP 1 LASTPIN (-7100 4825) BN 12
J 0
(-7112 4833);
DISPLAY 0.680851 (-7112 4833);
PAINT GREEN (-7112 4833);
FORCEPROP 2 LAST CDS_LIB standard
J 0
(-7050 4825);
DISPLAY INVISIBLE (-7050 4825);
FORCEPROP 1 LAST BODY_TYPE PLUMBING
J 0
(-7050 4875);
DISPLAY 0.872340 (-7050 4875);
PAINT GREEN (-7050 4875);
DISPLAY INVISIBLE (-7050 4875);
FORCEPROP 1 LAST HDL_TAP TRUE
J 0
(-6725 4700);
DISPLAY 0.872340 (-6725 4700);
DISPLAY INVISIBLE (-6725 4700);
FORCEPROP 1 LAST PATH I63
J 0
(-7052 4825);
DISPLAY 0.872340 (-7052 4825);
PAINT GREEN (-7052 4825);
DISPLAY INVISIBLE (-7052 4825);
FORCEADD TAP..1
(-6850 4375);
FORCEPROP 3 LASTPIN (-6900 4375) SIG_NAME P5E_CPU1_P2_TX_BUF_DN<11>
J 0
(-6890 4385);
DISPLAY 0.659574 (-6890 4385);
PAINT MONO (-6890 4385);
DISPLAY INVISIBLE (-6890 4385);
FORCEPROP 1 LASTPIN (-6900 4375) BN 11
J 0
(-6912 4383);
DISPLAY 0.680851 (-6912 4383);
PAINT GREEN (-6912 4383);
FORCEPROP 2 LAST CDS_LIB standard
J 0
(-6850 4375);
DISPLAY INVISIBLE (-6850 4375);
FORCEPROP 1 LAST BODY_TYPE PLUMBING
J 0
(-6850 4425);
DISPLAY 0.872340 (-6850 4425);
PAINT GREEN (-6850 4425);
DISPLAY INVISIBLE (-6850 4425);
FORCEPROP 1 LAST HDL_TAP TRUE
J 0
(-6525 4250);
DISPLAY 0.872340 (-6525 4250);
DISPLAY INVISIBLE (-6525 4250);
FORCEPROP 1 LAST PATH I64
J 0
(-6852 4375);
DISPLAY 0.872340 (-6852 4375);
PAINT GREEN (-6852 4375);
DISPLAY INVISIBLE (-6852 4375);
FORCEADD TAP..1
(-6850 4725);
FORCEPROP 3 LASTPIN (-6900 4725) SIG_NAME P5E_CPU1_P2_TX_BUF_DN<12>
J 0
(-6890 4735);
DISPLAY 0.659574 (-6890 4735);
PAINT MONO (-6890 4735);
DISPLAY INVISIBLE (-6890 4735);
FORCEPROP 1 LASTPIN (-6900 4725) BN 12
J 0
(-6912 4733);
DISPLAY 0.680851 (-6912 4733);
PAINT GREEN (-6912 4733);
FORCEPROP 2 LAST CDS_LIB standard
J 0
(-6850 4725);
DISPLAY INVISIBLE (-6850 4725);
FORCEPROP 1 LAST BODY_TYPE PLUMBING
J 0
(-6850 4775);
DISPLAY 0.872340 (-6850 4775);
PAINT GREEN (-6850 4775);
DISPLAY INVISIBLE (-6850 4775);
FORCEPROP 1 LAST HDL_TAP TRUE
J 0
(-6525 4600);
DISPLAY 0.872340 (-6525 4600);
DISPLAY INVISIBLE (-6525 4600);
FORCEPROP 1 LAST PATH I65
J 0
(-6852 4725);
DISPLAY 0.872340 (-6852 4725);
PAINT GREEN (-6852 4725);
DISPLAY INVISIBLE (-6852 4725);
FORCEADD TAP..1
(-6850 5075);
FORCEPROP 3 LASTPIN (-6900 5075) SIG_NAME P5E_CPU1_P2_TX_BUF_DN<13>
J 0
(-6890 5085);
DISPLAY 0.659574 (-6890 5085);
PAINT MONO (-6890 5085);
DISPLAY INVISIBLE (-6890 5085);
FORCEPROP 1 LASTPIN (-6900 5075) BN 13
J 0
(-6912 5083);
DISPLAY 0.680851 (-6912 5083);
PAINT GREEN (-6912 5083);
FORCEPROP 2 LAST CDS_LIB standard
J 0
(-6850 5075);
DISPLAY INVISIBLE (-6850 5075);
FORCEPROP 1 LAST BODY_TYPE PLUMBING
J 0
(-6850 5125);
DISPLAY 0.872340 (-6850 5125);
PAINT GREEN (-6850 5125);
DISPLAY INVISIBLE (-6850 5125);
FORCEPROP 1 LAST HDL_TAP TRUE
J 0
(-6525 4950);
DISPLAY 0.872340 (-6525 4950);
DISPLAY INVISIBLE (-6525 4950);
FORCEPROP 1 LAST PATH I66
J 0
(-6852 5075);
DISPLAY 0.872340 (-6852 5075);
PAINT GREEN (-6852 5075);
DISPLAY INVISIBLE (-6852 5075);
FORCEADD TAP..1
(-7050 5175);
FORCEPROP 3 LASTPIN (-7100 5175) SIG_NAME P5E_CPU1_P2_TX_BUF_DP<13>
J 0
(-7090 5185);
DISPLAY 0.659574 (-7090 5185);
PAINT MONO (-7090 5185);
DISPLAY INVISIBLE (-7090 5185);
FORCEPROP 1 LASTPIN (-7100 5175) BN 13
J 0
(-7112 5183);
DISPLAY 0.680851 (-7112 5183);
PAINT GREEN (-7112 5183);
FORCEPROP 2 LAST CDS_LIB standard
J 0
(-7050 5175);
DISPLAY INVISIBLE (-7050 5175);
FORCEPROP 1 LAST BODY_TYPE PLUMBING
J 0
(-7050 5225);
DISPLAY 0.872340 (-7050 5225);
PAINT GREEN (-7050 5225);
DISPLAY INVISIBLE (-7050 5225);
FORCEPROP 1 LAST HDL_TAP TRUE
J 0
(-6725 5050);
DISPLAY 0.872340 (-6725 5050);
DISPLAY INVISIBLE (-6725 5050);
FORCEPROP 1 LAST PATH I67
J 0
(-7052 5175);
DISPLAY 0.872340 (-7052 5175);
PAINT GREEN (-7052 5175);
DISPLAY INVISIBLE (-7052 5175);
FORCEADD TAP..1
(-7050 5525);
FORCEPROP 3 LASTPIN (-7100 5525) SIG_NAME P5E_CPU1_P2_TX_BUF_DP<14>
J 0
(-7090 5535);
DISPLAY 0.659574 (-7090 5535);
PAINT MONO (-7090 5535);
DISPLAY INVISIBLE (-7090 5535);
FORCEPROP 1 LASTPIN (-7100 5525) BN 14
J 0
(-7112 5533);
DISPLAY 0.680851 (-7112 5533);
PAINT GREEN (-7112 5533);
FORCEPROP 2 LAST CDS_LIB standard
J 0
(-7050 5525);
DISPLAY INVISIBLE (-7050 5525);
FORCEPROP 1 LAST BODY_TYPE PLUMBING
J 0
(-7050 5575);
DISPLAY 0.872340 (-7050 5575);
PAINT GREEN (-7050 5575);
DISPLAY INVISIBLE (-7050 5575);
FORCEPROP 1 LAST HDL_TAP TRUE
J 0
(-6725 5400);
DISPLAY 0.872340 (-6725 5400);
DISPLAY INVISIBLE (-6725 5400);
FORCEPROP 1 LAST PATH I68
J 0
(-7052 5525);
DISPLAY 0.872340 (-7052 5525);
PAINT GREEN (-7052 5525);
DISPLAY INVISIBLE (-7052 5525);
FORCEADD TAP..1
(-7050 5875);
FORCEPROP 3 LASTPIN (-7100 5875) SIG_NAME P5E_CPU1_P2_TX_BUF_DP<15>
J 0
(-7090 5885);
DISPLAY 0.659574 (-7090 5885);
PAINT MONO (-7090 5885);
DISPLAY INVISIBLE (-7090 5885);
FORCEPROP 1 LASTPIN (-7100 5875) BN 15
J 0
(-7112 5883);
DISPLAY 0.680851 (-7112 5883);
PAINT GREEN (-7112 5883);
FORCEPROP 2 LAST CDS_LIB standard
J 0
(-7050 5875);
DISPLAY INVISIBLE (-7050 5875);
FORCEPROP 1 LAST BODY_TYPE PLUMBING
J 0
(-7050 5925);
DISPLAY 0.872340 (-7050 5925);
PAINT GREEN (-7050 5925);
DISPLAY INVISIBLE (-7050 5925);
FORCEPROP 1 LAST HDL_TAP TRUE
J 0
(-6725 5750);
DISPLAY 0.872340 (-6725 5750);
DISPLAY INVISIBLE (-6725 5750);
FORCEPROP 1 LAST PATH I69
J 0
(-7052 5875);
DISPLAY 0.872340 (-7052 5875);
PAINT GREEN (-7052 5875);
DISPLAY INVISIBLE (-7052 5875);
FORCEADD TAP..1
R 2
(-3300 1125);
FORCEPROP 3 LASTPIN (-3250 1125) SIG_NAME P5E_CPU1_P2_TX_BUF_DN<5>
J 0
(-3240 1135);
DISPLAY 0.659574 (-3240 1135);
PAINT MONO (-3240 1135);
DISPLAY INVISIBLE (-3240 1135);
FORCEPROP 1 LASTPIN (-3250 1125) BN 5
J 2
(-3238 1133);
DISPLAY 0.680851 (-3238 1133);
PAINT GREEN (-3238 1133);
FORCEPROP 2 LAST CDS_LIB standard
J 0
(-3300 1125);
DISPLAY INVISIBLE (-3300 1125);
FORCEPROP 1 LAST BODY_TYPE PLUMBING
J 2
(-3300 1175);
DISPLAY 0.872340 (-3300 1175);
PAINT GREEN (-3300 1175);
DISPLAY INVISIBLE (-3300 1175);
FORCEPROP 1 LAST HDL_TAP TRUE
J 2
(-3625 1000);
DISPLAY 0.872340 (-3625 1000);
DISPLAY INVISIBLE (-3625 1000);
FORCEPROP 1 LAST PATH I7
J 2
(-3298 1125);
DISPLAY 0.872340 (-3298 1125);
PAINT GREEN (-3298 1125);
DISPLAY INVISIBLE (-3298 1125);
FORCEADD TAP..1
(-6850 5425);
FORCEPROP 3 LASTPIN (-6900 5425) SIG_NAME P5E_CPU1_P2_TX_BUF_DN<14>
J 0
(-6890 5435);
DISPLAY 0.659574 (-6890 5435);
PAINT MONO (-6890 5435);
DISPLAY INVISIBLE (-6890 5435);
FORCEPROP 1 LASTPIN (-6900 5425) BN 14
J 0
(-6912 5433);
DISPLAY 0.680851 (-6912 5433);
PAINT GREEN (-6912 5433);
FORCEPROP 2 LAST CDS_LIB standard
J 0
(-6850 5425);
DISPLAY INVISIBLE (-6850 5425);
FORCEPROP 1 LAST BODY_TYPE PLUMBING
J 0
(-6850 5475);
DISPLAY 0.872340 (-6850 5475);
PAINT GREEN (-6850 5475);
DISPLAY INVISIBLE (-6850 5475);
FORCEPROP 1 LAST HDL_TAP TRUE
J 0
(-6525 5300);
DISPLAY 0.872340 (-6525 5300);
DISPLAY INVISIBLE (-6525 5300);
FORCEPROP 1 LAST PATH I70
J 0
(-6852 5425);
DISPLAY 0.872340 (-6852 5425);
PAINT GREEN (-6852 5425);
DISPLAY INVISIBLE (-6852 5425);
FORCEADD TAP..1
(-6850 5775);
FORCEPROP 3 LASTPIN (-6900 5775) SIG_NAME P5E_CPU1_P2_TX_BUF_DN<15>
J 0
(-6890 5785);
DISPLAY 0.659574 (-6890 5785);
PAINT MONO (-6890 5785);
DISPLAY INVISIBLE (-6890 5785);
FORCEPROP 1 LASTPIN (-6900 5775) BN 15
J 0
(-6912 5783);
DISPLAY 0.680851 (-6912 5783);
PAINT GREEN (-6912 5783);
FORCEPROP 2 LAST CDS_LIB standard
J 0
(-6850 5775);
DISPLAY INVISIBLE (-6850 5775);
FORCEPROP 1 LAST BODY_TYPE PLUMBING
J 0
(-6850 5825);
DISPLAY 0.872340 (-6850 5825);
PAINT GREEN (-6850 5825);
DISPLAY INVISIBLE (-6850 5825);
FORCEPROP 1 LAST HDL_TAP TRUE
J 0
(-6525 5650);
DISPLAY 0.872340 (-6525 5650);
DISPLAY INVISIBLE (-6525 5650);
FORCEPROP 1 LAST PATH I71
J 0
(-6852 5775);
DISPLAY 0.872340 (-6852 5775);
PAINT GREEN (-6852 5775);
DISPLAY INVISIBLE (-6852 5775);
FORCEADD OFFPAGE..5
R 2
(-5850 5900);
FORCEPROP 2 LAST $XR0 342 
J 0
(-5661 5900);
DISPLAY 0.638298 (-5661 5900);
PAINT MONO (-5661 5900);
FORCEPROP 2 LAST CDS_LIB standard
J 0
(-5850 5900);
DISPLAY INVISIBLE (-5850 5900);
FORCEPROP 1 LAST OFFPAGE TRUE
J 2
(-6175 5775);
DISPLAY 0.872340 (-6175 5775);
PAINT GREEN (-6175 5775);
DISPLAY INVISIBLE (-6175 5775);
FORCEPROP 1 LAST COMMENT_BODY TRUE
J 2
(-5950 5825);
DISPLAY 0.872340 (-5950 5825);
PAINT GREEN (-5950 5825);
DISPLAY INVISIBLE (-5950 5825);
FORCEPROP 2 LAST PATH I72
J 0
(-5675 5975);
DISPLAY 0.680851 (-5675 5975);
DISPLAY INVISIBLE (-5675 5975);
FORCEADD OFFPAGE..5
R 2
(-5875 5800);
FORCEPROP 2 LAST $XR0 342 
J 0
(-5686 5800);
DISPLAY 0.638298 (-5686 5800);
PAINT MONO (-5686 5800);
FORCEPROP 2 LAST CDS_LIB standard
J 0
(-5875 5800);
DISPLAY INVISIBLE (-5875 5800);
FORCEPROP 1 LAST OFFPAGE TRUE
J 2
(-6200 5675);
DISPLAY 0.872340 (-6200 5675);
PAINT GREEN (-6200 5675);
DISPLAY INVISIBLE (-6200 5675);
FORCEPROP 1 LAST COMMENT_BODY TRUE
J 2
(-5975 5725);
DISPLAY 0.872340 (-5975 5725);
PAINT GREEN (-5975 5725);
DISPLAY INVISIBLE (-5975 5725);
FORCEPROP 2 LAST PATH I73
J 0
(-5700 5875);
DISPLAY 0.680851 (-5700 5875);
DISPLAY INVISIBLE (-5700 5875);
FORCEADD TAP..1
R 2
(-8075 800);
FORCEPROP 3 LASTPIN (-8025 800) SIG_NAME P5E_CPU1_P2_TX_BUF_DN<15>
J 0
(-8015 810);
DISPLAY 0.659574 (-8015 810);
PAINT MONO (-8015 810);
DISPLAY INVISIBLE (-8015 810);
FORCEPROP 1 LASTPIN (-8025 800) BN 15
J 2
(-8013 808);
DISPLAY 0.680851 (-8013 808);
PAINT GREEN (-8013 808);
FORCEPROP 2 LAST CDS_LIB standard
J 0
(-8075 800);
DISPLAY INVISIBLE (-8075 800);
FORCEPROP 1 LAST BODY_TYPE PLUMBING
J 2
(-8075 850);
DISPLAY 0.872340 (-8075 850);
PAINT GREEN (-8075 850);
DISPLAY INVISIBLE (-8075 850);
FORCEPROP 1 LAST HDL_TAP TRUE
J 2
(-8400 675);
DISPLAY 0.872340 (-8400 675);
DISPLAY INVISIBLE (-8400 675);
FORCEPROP 1 LAST PATH I74
J 2
(-8073 800);
DISPLAY 0.872340 (-8073 800);
PAINT GREEN (-8073 800);
DISPLAY INVISIBLE (-8073 800);
FORCEADD TAP..1
R 2
(-8075 1000);
FORCEPROP 3 LASTPIN (-8025 1000) SIG_NAME P5E_CPU1_P2_TX_BUF_DN<14>
J 0
(-8015 1010);
DISPLAY 0.659574 (-8015 1010);
PAINT MONO (-8015 1010);
DISPLAY INVISIBLE (-8015 1010);
FORCEPROP 1 LASTPIN (-8025 1000) BN 14
J 2
(-8013 1008);
DISPLAY 0.680851 (-8013 1008);
PAINT GREEN (-8013 1008);
FORCEPROP 2 LAST CDS_LIB standard
J 0
(-8075 1000);
DISPLAY INVISIBLE (-8075 1000);
FORCEPROP 1 LAST BODY_TYPE PLUMBING
J 2
(-8075 1050);
DISPLAY 0.872340 (-8075 1050);
PAINT GREEN (-8075 1050);
DISPLAY INVISIBLE (-8075 1050);
FORCEPROP 1 LAST HDL_TAP TRUE
J 2
(-8400 875);
DISPLAY 0.872340 (-8400 875);
DISPLAY INVISIBLE (-8400 875);
FORCEPROP 1 LAST PATH I75
J 2
(-8073 1000);
DISPLAY 0.872340 (-8073 1000);
PAINT GREEN (-8073 1000);
DISPLAY INVISIBLE (-8073 1000);
FORCEADD TAP..1
R 2
(-8075 1200);
FORCEPROP 3 LASTPIN (-8025 1200) SIG_NAME P5E_CPU1_P2_TX_BUF_DN<13>
J 0
(-8015 1210);
DISPLAY 0.659574 (-8015 1210);
PAINT MONO (-8015 1210);
DISPLAY INVISIBLE (-8015 1210);
FORCEPROP 1 LASTPIN (-8025 1200) BN 13
J 2
(-8013 1208);
DISPLAY 0.680851 (-8013 1208);
PAINT GREEN (-8013 1208);
FORCEPROP 2 LAST CDS_LIB standard
J 0
(-8075 1200);
DISPLAY INVISIBLE (-8075 1200);
FORCEPROP 1 LAST BODY_TYPE PLUMBING
J 2
(-8075 1250);
DISPLAY 0.872340 (-8075 1250);
PAINT GREEN (-8075 1250);
DISPLAY INVISIBLE (-8075 1250);
FORCEPROP 1 LAST HDL_TAP TRUE
J 2
(-8400 1075);
DISPLAY 0.872340 (-8400 1075);
DISPLAY INVISIBLE (-8400 1075);
FORCEPROP 1 LAST PATH I76
J 2
(-8073 1200);
DISPLAY 0.872340 (-8073 1200);
PAINT GREEN (-8073 1200);
DISPLAY INVISIBLE (-8073 1200);
FORCEADD TAP..1
R 2
(-8075 1600);
FORCEPROP 3 LASTPIN (-8025 1600) SIG_NAME P5E_CPU1_P2_TX_BUF_DN<11>
J 0
(-8015 1610);
DISPLAY 0.659574 (-8015 1610);
PAINT MONO (-8015 1610);
DISPLAY INVISIBLE (-8015 1610);
FORCEPROP 1 LASTPIN (-8025 1600) BN 11
J 2
(-8013 1608);
DISPLAY 0.680851 (-8013 1608);
PAINT GREEN (-8013 1608);
FORCEPROP 2 LAST CDS_LIB standard
J 0
(-8075 1600);
DISPLAY INVISIBLE (-8075 1600);
FORCEPROP 1 LAST BODY_TYPE PLUMBING
J 2
(-8075 1650);
DISPLAY 0.872340 (-8075 1650);
PAINT GREEN (-8075 1650);
DISPLAY INVISIBLE (-8075 1650);
FORCEPROP 1 LAST HDL_TAP TRUE
J 2
(-8400 1475);
DISPLAY 0.872340 (-8400 1475);
DISPLAY INVISIBLE (-8400 1475);
FORCEPROP 1 LAST PATH I77
J 2
(-8073 1600);
DISPLAY 0.872340 (-8073 1600);
PAINT GREEN (-8073 1600);
DISPLAY INVISIBLE (-8073 1600);
FORCEADD TAP..1
R 2
(-8075 1400);
FORCEPROP 3 LASTPIN (-8025 1400) SIG_NAME P5E_CPU1_P2_TX_BUF_DN<12>
J 0
(-8015 1410);
DISPLAY 0.659574 (-8015 1410);
PAINT MONO (-8015 1410);
DISPLAY INVISIBLE (-8015 1410);
FORCEPROP 1 LASTPIN (-8025 1400) BN 12
J 2
(-8013 1408);
DISPLAY 0.680851 (-8013 1408);
PAINT GREEN (-8013 1408);
FORCEPROP 2 LAST CDS_LIB standard
J 0
(-8075 1400);
DISPLAY INVISIBLE (-8075 1400);
FORCEPROP 1 LAST BODY_TYPE PLUMBING
J 2
(-8075 1450);
DISPLAY 0.872340 (-8075 1450);
PAINT GREEN (-8075 1450);
DISPLAY INVISIBLE (-8075 1450);
FORCEPROP 1 LAST HDL_TAP TRUE
J 2
(-8400 1275);
DISPLAY 0.872340 (-8400 1275);
DISPLAY INVISIBLE (-8400 1275);
FORCEPROP 1 LAST PATH I78
J 2
(-8073 1400);
DISPLAY 0.872340 (-8073 1400);
PAINT GREEN (-8073 1400);
DISPLAY INVISIBLE (-8073 1400);
FORCEADD TAP..1
R 2
(-8075 1800);
FORCEPROP 3 LASTPIN (-8025 1800) SIG_NAME P5E_CPU1_P2_TX_BUF_DN<10>
J 0
(-8015 1810);
DISPLAY 0.659574 (-8015 1810);
PAINT MONO (-8015 1810);
DISPLAY INVISIBLE (-8015 1810);
FORCEPROP 1 LASTPIN (-8025 1800) BN 10
J 2
(-8013 1808);
DISPLAY 0.680851 (-8013 1808);
PAINT GREEN (-8013 1808);
FORCEPROP 2 LAST CDS_LIB standard
J 0
(-8075 1800);
DISPLAY INVISIBLE (-8075 1800);
FORCEPROP 1 LAST BODY_TYPE PLUMBING
J 2
(-8075 1850);
DISPLAY 0.872340 (-8075 1850);
PAINT GREEN (-8075 1850);
DISPLAY INVISIBLE (-8075 1850);
FORCEPROP 1 LAST HDL_TAP TRUE
J 2
(-8400 1675);
DISPLAY 0.872340 (-8400 1675);
DISPLAY INVISIBLE (-8400 1675);
FORCEPROP 1 LAST PATH I79
J 2
(-8073 1800);
DISPLAY 0.872340 (-8073 1800);
PAINT GREEN (-8073 1800);
DISPLAY INVISIBLE (-8073 1800);
FORCEADD TAP..1
R 2
(-3300 1325);
FORCEPROP 3 LASTPIN (-3250 1325) SIG_NAME P5E_CPU1_P2_TX_BUF_DN<4>
J 0
(-3240 1335);
DISPLAY 0.659574 (-3240 1335);
PAINT MONO (-3240 1335);
DISPLAY INVISIBLE (-3240 1335);
FORCEPROP 1 LASTPIN (-3250 1325) BN 4
J 2
(-3238 1333);
DISPLAY 0.680851 (-3238 1333);
PAINT GREEN (-3238 1333);
FORCEPROP 2 LAST CDS_LIB standard
J 0
(-3300 1325);
DISPLAY INVISIBLE (-3300 1325);
FORCEPROP 1 LAST BODY_TYPE PLUMBING
J 2
(-3300 1375);
DISPLAY 0.872340 (-3300 1375);
PAINT GREEN (-3300 1375);
DISPLAY INVISIBLE (-3300 1375);
FORCEPROP 1 LAST HDL_TAP TRUE
J 2
(-3625 1200);
DISPLAY 0.872340 (-3625 1200);
DISPLAY INVISIBLE (-3625 1200);
FORCEPROP 1 LAST PATH I8
J 2
(-3298 1325);
DISPLAY 0.872340 (-3298 1325);
PAINT GREEN (-3298 1325);
DISPLAY INVISIBLE (-3298 1325);
FORCEADD TAP..1
R 2
(-7825 850);
FORCEPROP 3 LASTPIN (-7775 850) SIG_NAME P5E_CPU1_P2_TX_BUF_DP<15>
J 0
(-7765 860);
DISPLAY 0.659574 (-7765 860);
PAINT MONO (-7765 860);
DISPLAY INVISIBLE (-7765 860);
FORCEPROP 1 LASTPIN (-7775 850) BN 15
J 2
(-7763 858);
DISPLAY 0.680851 (-7763 858);
PAINT GREEN (-7763 858);
FORCEPROP 2 LAST CDS_LIB standard
J 0
(-7825 850);
DISPLAY INVISIBLE (-7825 850);
FORCEPROP 1 LAST BODY_TYPE PLUMBING
J 2
(-7825 900);
DISPLAY 0.872340 (-7825 900);
PAINT GREEN (-7825 900);
DISPLAY INVISIBLE (-7825 900);
FORCEPROP 1 LAST HDL_TAP TRUE
J 2
(-8150 725);
DISPLAY 0.872340 (-8150 725);
DISPLAY INVISIBLE (-8150 725);
FORCEPROP 1 LAST PATH I80
J 2
(-7823 850);
DISPLAY 0.872340 (-7823 850);
PAINT GREEN (-7823 850);
DISPLAY INVISIBLE (-7823 850);
FORCEADD Q_CAP_DIFFBUS..2
R 2
(-7100 800);
FORCEPROP 1 LAST LOCATION C6724
J 2
(-6825 800);
DISPLAY 0.723404 (-6825 800);
PAINT GREEN (-6825 800);
FORCEPROP 2 LAST $SEC 1
J 2
(-6925 875);
DISPLAY 0.680851 (-6925 875);
PAINT MONO (-6925 875);
DISPLAY INVISIBLE (-6925 875);
FORCEPROP 2 LAST CDS_SEC 1
J 2
(-6925 875);
DISPLAY 0.680851 (-6925 875);
DISPLAY INVISIBLE (-6925 875);
FORCEPROP 2 LASTPIN (-7025 800) $PN 1
J 0
(-7015 810);
DISPLAY 0.808511 (-7015 810);
FORCEPROP 2 LASTPIN (-7175 800) $PN 2
J 2
(-7185 810);
DISPLAY 0.808511 (-7185 810);
FORCEPROP 2 LAST VALUE DIFF BUS_0.22UF
J 2
(-7250 800);
DISPLAY 0.553191 (-7250 800);
FORCEPROP 1 LAST CDS_LMAN_SYM_OUTLINE -25,50,25,-50
J 2
(-7100 800);
DISPLAY 0.468085 (-7100 800);
PAINT GREEN (-7100 800);
DISPLAY INVISIBLE (-7100 800);
FORCEPROP 2 LAST CDS_LIB pure_quanta
J 2
(-7100 800);
DISPLAY INVISIBLE (-7100 800);
FORCEPROP 1 LAST PIN_NAMES_ROTATE TRUE
J 2
(-7100 800);
DISPLAY 0.489362 (-7100 800);
PAINT GREEN (-7100 800);
DISPLAY INVISIBLE (-7100 800);
FORCEPROP 2 LAST VOLTAGE 6.3V
J 2
(-7450 850);
DISPLAY 0.553191 (-7450 850);
DISPLAY INVISIBLE (-7450 850);
FORCEPROP 1 LAST MATERIAL X6S
J 2
(-7091 879);
DISPLAY 0.574468 (-7091 879);
PAINT GREEN (-7091 879);
DISPLAY INVISIBLE (-7091 879);
FORCEPROP 2 LAST PACK_TYPE C0201
J 2
(-7275 850);
DISPLAY 0.553191 (-7275 850);
DISPLAY INVISIBLE (-7275 850);
FORCEPROP 2 LAST TOLERANCE 20%
J 2
(-7175 850);
DISPLAY 0.553191 (-7175 850);
DISPLAY INVISIBLE (-7175 850);
FORCEPROP 1 LAST PATH I81
J 2
(-7100 800);
DISPLAY 0.723404 (-7100 800);
DISPLAY INVISIBLE (-7100 800);
FORCEPROP 1 LAST PART_NUMBER SP_CH4221MEE01
J 2
(-7216 888);
DISPLAY 0.574468 (-7216 888);
PAINT GREEN (-7216 888);
DISPLAY INVISIBLE (-7216 888);
FORCEPROP 1 LAST LOCATION C6724
J 0
(-6850 875);
DISPLAY 1.021277 (-6850 875);
DISPLAY INVISIBLE (-6850 875);
FORCEADD Q_CAP_DIFFBUS..2
R 2
(-7100 850);
FORCEPROP 1 LAST LOCATION C6723
J 2
(-6825 850);
DISPLAY 0.723404 (-6825 850);
PAINT GREEN (-6825 850);
FORCEPROP 2 LAST $SEC 1
J 2
(-6925 925);
DISPLAY 0.680851 (-6925 925);
PAINT MONO (-6925 925);
DISPLAY INVISIBLE (-6925 925);
FORCEPROP 2 LAST CDS_SEC 1
J 2
(-6925 925);
DISPLAY 0.680851 (-6925 925);
DISPLAY INVISIBLE (-6925 925);
FORCEPROP 2 LASTPIN (-7025 850) $PN 1
J 0
(-7015 860);
DISPLAY 0.808511 (-7015 860);
FORCEPROP 2 LASTPIN (-7175 850) $PN 2
J 2
(-7185 860);
DISPLAY 0.808511 (-7185 860);
FORCEPROP 2 LAST VALUE DIFF BUS_0.22UF
J 2
(-7250 850);
DISPLAY 0.553191 (-7250 850);
FORCEPROP 1 LAST CDS_LMAN_SYM_OUTLINE -25,50,25,-50
J 2
(-7100 850);
DISPLAY 0.468085 (-7100 850);
PAINT GREEN (-7100 850);
DISPLAY INVISIBLE (-7100 850);
FORCEPROP 2 LAST CDS_LIB pure_quanta
J 2
(-7100 850);
DISPLAY INVISIBLE (-7100 850);
FORCEPROP 1 LAST PIN_NAMES_ROTATE TRUE
J 2
(-7100 850);
DISPLAY 0.489362 (-7100 850);
PAINT GREEN (-7100 850);
DISPLAY INVISIBLE (-7100 850);
FORCEPROP 2 LAST VOLTAGE 6.3V
J 2
(-7450 900);
DISPLAY 0.553191 (-7450 900);
DISPLAY INVISIBLE (-7450 900);
FORCEPROP 1 LAST MATERIAL X6S
J 2
(-7091 929);
DISPLAY 0.574468 (-7091 929);
PAINT GREEN (-7091 929);
DISPLAY INVISIBLE (-7091 929);
FORCEPROP 2 LAST PACK_TYPE C0201
J 2
(-7275 900);
DISPLAY 0.553191 (-7275 900);
DISPLAY INVISIBLE (-7275 900);
FORCEPROP 2 LAST TOLERANCE 20%
J 2
(-7175 900);
DISPLAY 0.553191 (-7175 900);
DISPLAY INVISIBLE (-7175 900);
FORCEPROP 1 LAST PATH I82
J 2
(-7100 850);
DISPLAY 0.723404 (-7100 850);
DISPLAY INVISIBLE (-7100 850);
FORCEPROP 1 LAST PART_NUMBER SP_CH4221MEE01
J 2
(-7216 938);
DISPLAY 0.574468 (-7216 938);
PAINT GREEN (-7216 938);
DISPLAY INVISIBLE (-7216 938);
FORCEPROP 1 LAST LOCATION C6723
J 0
(-6850 925);
DISPLAY 1.021277 (-6850 925);
DISPLAY INVISIBLE (-6850 925);
FORCEADD Q_CAP_DIFFBUS..2
R 2
(-7100 1000);
FORCEPROP 1 LAST LOCATION C6722
J 2
(-6825 1000);
DISPLAY 0.723404 (-6825 1000);
PAINT GREEN (-6825 1000);
FORCEPROP 2 LAST $SEC 1
J 2
(-6925 1075);
DISPLAY 0.680851 (-6925 1075);
PAINT MONO (-6925 1075);
DISPLAY INVISIBLE (-6925 1075);
FORCEPROP 2 LAST CDS_SEC 1
J 2
(-6925 1075);
DISPLAY 0.680851 (-6925 1075);
DISPLAY INVISIBLE (-6925 1075);
FORCEPROP 2 LASTPIN (-7025 1000) $PN 1
J 0
(-7015 1010);
DISPLAY 0.808511 (-7015 1010);
FORCEPROP 2 LASTPIN (-7175 1000) $PN 2
J 2
(-7185 1010);
DISPLAY 0.808511 (-7185 1010);
FORCEPROP 2 LAST VALUE DIFF BUS_0.22UF
J 2
(-7250 1000);
DISPLAY 0.553191 (-7250 1000);
FORCEPROP 1 LAST CDS_LMAN_SYM_OUTLINE -25,50,25,-50
J 2
(-7100 1000);
DISPLAY 0.468085 (-7100 1000);
PAINT GREEN (-7100 1000);
DISPLAY INVISIBLE (-7100 1000);
FORCEPROP 2 LAST CDS_LIB pure_quanta
J 2
(-7100 1000);
DISPLAY INVISIBLE (-7100 1000);
FORCEPROP 1 LAST PIN_NAMES_ROTATE TRUE
J 2
(-7100 1000);
DISPLAY 0.489362 (-7100 1000);
PAINT GREEN (-7100 1000);
DISPLAY INVISIBLE (-7100 1000);
FORCEPROP 2 LAST VOLTAGE 6.3V
J 2
(-7450 1050);
DISPLAY 0.553191 (-7450 1050);
DISPLAY INVISIBLE (-7450 1050);
FORCEPROP 1 LAST MATERIAL X6S
J 2
(-7091 1079);
DISPLAY 0.574468 (-7091 1079);
PAINT GREEN (-7091 1079);
DISPLAY INVISIBLE (-7091 1079);
FORCEPROP 2 LAST PACK_TYPE C0201
J 2
(-7275 1050);
DISPLAY 0.553191 (-7275 1050);
DISPLAY INVISIBLE (-7275 1050);
FORCEPROP 2 LAST TOLERANCE 20%
J 2
(-7175 1050);
DISPLAY 0.553191 (-7175 1050);
DISPLAY INVISIBLE (-7175 1050);
FORCEPROP 1 LAST PATH I83
J 2
(-7100 1000);
DISPLAY 0.723404 (-7100 1000);
DISPLAY INVISIBLE (-7100 1000);
FORCEPROP 1 LAST PART_NUMBER SP_CH4221MEE01
J 2
(-7216 1088);
DISPLAY 0.574468 (-7216 1088);
PAINT GREEN (-7216 1088);
DISPLAY INVISIBLE (-7216 1088);
FORCEPROP 1 LAST LOCATION C6722
J 0
(-6850 1075);
DISPLAY 1.021277 (-6850 1075);
DISPLAY INVISIBLE (-6850 1075);
FORCEADD Q_CAP_DIFFBUS..2
R 2
(-7100 1050);
FORCEPROP 1 LAST LOCATION C6721
J 2
(-6825 1050);
DISPLAY 0.723404 (-6825 1050);
PAINT GREEN (-6825 1050);
FORCEPROP 2 LAST $SEC 1
J 2
(-6925 1125);
DISPLAY 0.680851 (-6925 1125);
PAINT MONO (-6925 1125);
DISPLAY INVISIBLE (-6925 1125);
FORCEPROP 2 LAST CDS_SEC 1
J 2
(-6925 1125);
DISPLAY 0.680851 (-6925 1125);
DISPLAY INVISIBLE (-6925 1125);
FORCEPROP 2 LASTPIN (-7025 1050) $PN 1
J 0
(-7015 1060);
DISPLAY 0.808511 (-7015 1060);
FORCEPROP 2 LASTPIN (-7175 1050) $PN 2
J 2
(-7185 1060);
DISPLAY 0.808511 (-7185 1060);
FORCEPROP 2 LAST VALUE DIFF BUS_0.22UF
J 2
(-7250 1050);
DISPLAY 0.553191 (-7250 1050);
FORCEPROP 2 LAST CDS_LIB pure_quanta
J 2
(-7100 1050);
DISPLAY INVISIBLE (-7100 1050);
FORCEPROP 1 LAST CDS_LMAN_SYM_OUTLINE -25,50,25,-50
J 2
(-7100 1050);
DISPLAY 0.468085 (-7100 1050);
PAINT GREEN (-7100 1050);
DISPLAY INVISIBLE (-7100 1050);
FORCEPROP 1 LAST PIN_NAMES_ROTATE TRUE
J 2
(-7100 1050);
DISPLAY 0.489362 (-7100 1050);
PAINT GREEN (-7100 1050);
DISPLAY INVISIBLE (-7100 1050);
FORCEPROP 2 LAST VOLTAGE 6.3V
J 2
(-7450 1100);
DISPLAY 0.553191 (-7450 1100);
DISPLAY INVISIBLE (-7450 1100);
FORCEPROP 1 LAST MATERIAL X6S
J 2
(-7091 1129);
DISPLAY 0.574468 (-7091 1129);
PAINT GREEN (-7091 1129);
DISPLAY INVISIBLE (-7091 1129);
FORCEPROP 2 LAST PACK_TYPE C0201
J 2
(-7275 1100);
DISPLAY 0.553191 (-7275 1100);
DISPLAY INVISIBLE (-7275 1100);
FORCEPROP 2 LAST TOLERANCE 20%
J 2
(-7175 1100);
DISPLAY 0.553191 (-7175 1100);
DISPLAY INVISIBLE (-7175 1100);
FORCEPROP 1 LAST PATH I84
J 2
(-7100 1050);
DISPLAY 0.723404 (-7100 1050);
DISPLAY INVISIBLE (-7100 1050);
FORCEPROP 1 LAST PART_NUMBER SP_CH4221MEE01
J 2
(-7216 1138);
DISPLAY 0.574468 (-7216 1138);
PAINT GREEN (-7216 1138);
DISPLAY INVISIBLE (-7216 1138);
FORCEPROP 1 LAST LOCATION C6721
J 0
(-6850 1125);
DISPLAY 1.021277 (-6850 1125);
DISPLAY INVISIBLE (-6850 1125);
FORCEADD TAP..1
R 2
(-7825 1250);
FORCEPROP 3 LASTPIN (-7775 1250) SIG_NAME P5E_CPU1_P2_TX_BUF_DP<13>
J 0
(-7765 1260);
DISPLAY 0.659574 (-7765 1260);
PAINT MONO (-7765 1260);
DISPLAY INVISIBLE (-7765 1260);
FORCEPROP 1 LASTPIN (-7775 1250) BN 13
J 2
(-7763 1258);
DISPLAY 0.680851 (-7763 1258);
PAINT GREEN (-7763 1258);
FORCEPROP 2 LAST CDS_LIB standard
J 0
(-7825 1250);
DISPLAY INVISIBLE (-7825 1250);
FORCEPROP 1 LAST BODY_TYPE PLUMBING
J 2
(-7825 1300);
DISPLAY 0.872340 (-7825 1300);
PAINT GREEN (-7825 1300);
DISPLAY INVISIBLE (-7825 1300);
FORCEPROP 1 LAST HDL_TAP TRUE
J 2
(-8150 1125);
DISPLAY 0.872340 (-8150 1125);
DISPLAY INVISIBLE (-8150 1125);
FORCEPROP 1 LAST PATH I85
J 2
(-7823 1250);
DISPLAY 0.872340 (-7823 1250);
PAINT GREEN (-7823 1250);
DISPLAY INVISIBLE (-7823 1250);
FORCEADD TAP..1
R 2
(-7825 1450);
FORCEPROP 3 LASTPIN (-7775 1450) SIG_NAME P5E_CPU1_P2_TX_BUF_DP<12>
J 0
(-7765 1460);
DISPLAY 0.659574 (-7765 1460);
PAINT MONO (-7765 1460);
DISPLAY INVISIBLE (-7765 1460);
FORCEPROP 1 LASTPIN (-7775 1450) BN 12
J 2
(-7763 1458);
DISPLAY 0.680851 (-7763 1458);
PAINT GREEN (-7763 1458);
FORCEPROP 2 LAST CDS_LIB standard
J 0
(-7825 1450);
DISPLAY INVISIBLE (-7825 1450);
FORCEPROP 1 LAST BODY_TYPE PLUMBING
J 2
(-7825 1500);
DISPLAY 0.872340 (-7825 1500);
PAINT GREEN (-7825 1500);
DISPLAY INVISIBLE (-7825 1500);
FORCEPROP 1 LAST HDL_TAP TRUE
J 2
(-8150 1325);
DISPLAY 0.872340 (-8150 1325);
DISPLAY INVISIBLE (-8150 1325);
FORCEPROP 1 LAST PATH I86
J 2
(-7823 1450);
DISPLAY 0.872340 (-7823 1450);
PAINT GREEN (-7823 1450);
DISPLAY INVISIBLE (-7823 1450);
FORCEADD TAP..1
R 2
(-7825 1650);
FORCEPROP 3 LASTPIN (-7775 1650) SIG_NAME P5E_CPU1_P2_TX_BUF_DP<11>
J 0
(-7765 1660);
DISPLAY 0.659574 (-7765 1660);
PAINT MONO (-7765 1660);
DISPLAY INVISIBLE (-7765 1660);
FORCEPROP 1 LASTPIN (-7775 1650) BN 11
J 2
(-7763 1658);
DISPLAY 0.680851 (-7763 1658);
PAINT GREEN (-7763 1658);
FORCEPROP 2 LAST CDS_LIB standard
J 0
(-7825 1650);
DISPLAY INVISIBLE (-7825 1650);
FORCEPROP 1 LAST BODY_TYPE PLUMBING
J 2
(-7825 1700);
DISPLAY 0.872340 (-7825 1700);
PAINT GREEN (-7825 1700);
DISPLAY INVISIBLE (-7825 1700);
FORCEPROP 1 LAST HDL_TAP TRUE
J 2
(-8150 1525);
DISPLAY 0.872340 (-8150 1525);
DISPLAY INVISIBLE (-8150 1525);
FORCEPROP 1 LAST PATH I87
J 2
(-7823 1650);
DISPLAY 0.872340 (-7823 1650);
PAINT GREEN (-7823 1650);
DISPLAY INVISIBLE (-7823 1650);
FORCEADD TAP..1
R 2
(-7825 1850);
FORCEPROP 3 LASTPIN (-7775 1850) SIG_NAME P5E_CPU1_P2_TX_BUF_DP<10>
J 0
(-7765 1860);
DISPLAY 0.659574 (-7765 1860);
PAINT MONO (-7765 1860);
DISPLAY INVISIBLE (-7765 1860);
FORCEPROP 1 LASTPIN (-7775 1850) BN 10
J 2
(-7763 1858);
DISPLAY 0.680851 (-7763 1858);
PAINT GREEN (-7763 1858);
FORCEPROP 2 LAST CDS_LIB standard
J 0
(-7825 1850);
DISPLAY INVISIBLE (-7825 1850);
FORCEPROP 1 LAST BODY_TYPE PLUMBING
J 2
(-7825 1900);
DISPLAY 0.872340 (-7825 1900);
PAINT GREEN (-7825 1900);
DISPLAY INVISIBLE (-7825 1900);
FORCEPROP 1 LAST HDL_TAP TRUE
J 2
(-8150 1725);
DISPLAY 0.872340 (-8150 1725);
DISPLAY INVISIBLE (-8150 1725);
FORCEPROP 1 LAST PATH I88
J 2
(-7823 1850);
DISPLAY 0.872340 (-7823 1850);
PAINT GREEN (-7823 1850);
DISPLAY INVISIBLE (-7823 1850);
FORCEADD TAP..1
R 2
(-7825 2050);
FORCEPROP 3 LASTPIN (-7775 2050) SIG_NAME P5E_CPU1_P2_TX_BUF_DP<9>
J 0
(-7765 2060);
DISPLAY 0.659574 (-7765 2060);
PAINT MONO (-7765 2060);
DISPLAY INVISIBLE (-7765 2060);
FORCEPROP 1 LASTPIN (-7775 2050) BN 9
J 2
(-7763 2058);
DISPLAY 0.680851 (-7763 2058);
PAINT GREEN (-7763 2058);
FORCEPROP 2 LAST CDS_LIB standard
J 0
(-7825 2050);
DISPLAY INVISIBLE (-7825 2050);
FORCEPROP 1 LAST BODY_TYPE PLUMBING
J 2
(-7825 2100);
DISPLAY 0.872340 (-7825 2100);
PAINT GREEN (-7825 2100);
DISPLAY INVISIBLE (-7825 2100);
FORCEPROP 1 LAST HDL_TAP TRUE
J 2
(-8150 1925);
DISPLAY 0.872340 (-8150 1925);
DISPLAY INVISIBLE (-8150 1925);
FORCEPROP 1 LAST PATH I89
J 2
(-7823 2050);
DISPLAY 0.872340 (-7823 2050);
PAINT GREEN (-7823 2050);
DISPLAY INVISIBLE (-7823 2050);
FORCEADD TAP..1
R 2
(-3050 1175);
FORCEPROP 3 LASTPIN (-3000 1175) SIG_NAME P5E_CPU1_P2_TX_BUF_DP<5>
J 0
(-2990 1185);
DISPLAY 0.659574 (-2990 1185);
PAINT MONO (-2990 1185);
DISPLAY INVISIBLE (-2990 1185);
FORCEPROP 1 LASTPIN (-3000 1175) BN 5
J 2
(-2988 1183);
DISPLAY 0.680851 (-2988 1183);
PAINT GREEN (-2988 1183);
FORCEPROP 2 LAST CDS_LIB standard
J 0
(-3050 1175);
DISPLAY INVISIBLE (-3050 1175);
FORCEPROP 1 LAST BODY_TYPE PLUMBING
J 2
(-3050 1225);
DISPLAY 0.872340 (-3050 1225);
PAINT GREEN (-3050 1225);
DISPLAY INVISIBLE (-3050 1225);
FORCEPROP 1 LAST HDL_TAP TRUE
J 2
(-3375 1050);
DISPLAY 0.872340 (-3375 1050);
DISPLAY INVISIBLE (-3375 1050);
FORCEPROP 1 LAST PATH I9
J 2
(-3048 1175);
DISPLAY 0.872340 (-3048 1175);
PAINT GREEN (-3048 1175);
DISPLAY INVISIBLE (-3048 1175);
FORCEADD Q_CAP_DIFFBUS..2
R 2
(-7100 1200);
FORCEPROP 1 LAST LOCATION C6720
J 2
(-6825 1200);
DISPLAY 0.723404 (-6825 1200);
PAINT GREEN (-6825 1200);
FORCEPROP 2 LAST $SEC 1
J 2
(-6925 1275);
DISPLAY 0.680851 (-6925 1275);
PAINT MONO (-6925 1275);
DISPLAY INVISIBLE (-6925 1275);
FORCEPROP 2 LAST CDS_SEC 1
J 2
(-6925 1275);
DISPLAY 0.680851 (-6925 1275);
DISPLAY INVISIBLE (-6925 1275);
FORCEPROP 2 LASTPIN (-7025 1200) $PN 1
J 0
(-7015 1210);
DISPLAY 0.808511 (-7015 1210);
FORCEPROP 2 LASTPIN (-7175 1200) $PN 2
J 2
(-7185 1210);
DISPLAY 0.808511 (-7185 1210);
FORCEPROP 2 LAST VALUE DIFF BUS_0.22UF
J 2
(-7250 1200);
DISPLAY 0.553191 (-7250 1200);
FORCEPROP 1 LAST CDS_LMAN_SYM_OUTLINE -25,50,25,-50
J 2
(-7100 1200);
DISPLAY 0.468085 (-7100 1200);
PAINT GREEN (-7100 1200);
DISPLAY INVISIBLE (-7100 1200);
FORCEPROP 2 LAST CDS_LIB pure_quanta
J 2
(-7100 1200);
DISPLAY INVISIBLE (-7100 1200);
FORCEPROP 1 LAST PIN_NAMES_ROTATE TRUE
J 2
(-7100 1200);
DISPLAY 0.489362 (-7100 1200);
PAINT GREEN (-7100 1200);
DISPLAY INVISIBLE (-7100 1200);
FORCEPROP 2 LAST VOLTAGE 6.3V
J 2
(-7450 1250);
DISPLAY 0.553191 (-7450 1250);
DISPLAY INVISIBLE (-7450 1250);
FORCEPROP 1 LAST MATERIAL X6S
J 2
(-7091 1279);
DISPLAY 0.574468 (-7091 1279);
PAINT GREEN (-7091 1279);
DISPLAY INVISIBLE (-7091 1279);
FORCEPROP 2 LAST PACK_TYPE C0201
J 2
(-7275 1250);
DISPLAY 0.553191 (-7275 1250);
DISPLAY INVISIBLE (-7275 1250);
FORCEPROP 2 LAST TOLERANCE 20%
J 2
(-7175 1250);
DISPLAY 0.553191 (-7175 1250);
DISPLAY INVISIBLE (-7175 1250);
FORCEPROP 1 LAST PATH I90
J 2
(-7100 1200);
DISPLAY 0.723404 (-7100 1200);
DISPLAY INVISIBLE (-7100 1200);
FORCEPROP 1 LAST PART_NUMBER SP_CH4221MEE01
J 2
(-7216 1288);
DISPLAY 0.574468 (-7216 1288);
PAINT GREEN (-7216 1288);
DISPLAY INVISIBLE (-7216 1288);
FORCEPROP 1 LAST LOCATION C6720
J 0
(-6850 1275);
DISPLAY 1.021277 (-6850 1275);
DISPLAY INVISIBLE (-6850 1275);
FORCEADD Q_CAP_DIFFBUS..2
R 2
(-7100 1250);
FORCEPROP 1 LAST LOCATION C6719
J 2
(-6825 1250);
DISPLAY 0.723404 (-6825 1250);
PAINT GREEN (-6825 1250);
FORCEPROP 2 LAST $SEC 1
J 2
(-6925 1325);
DISPLAY 0.680851 (-6925 1325);
PAINT MONO (-6925 1325);
DISPLAY INVISIBLE (-6925 1325);
FORCEPROP 2 LAST CDS_SEC 1
J 2
(-6925 1325);
DISPLAY 0.680851 (-6925 1325);
DISPLAY INVISIBLE (-6925 1325);
FORCEPROP 2 LASTPIN (-7025 1250) $PN 1
J 0
(-7015 1260);
DISPLAY 0.808511 (-7015 1260);
FORCEPROP 2 LASTPIN (-7175 1250) $PN 2
J 2
(-7185 1260);
DISPLAY 0.808511 (-7185 1260);
FORCEPROP 2 LAST VALUE DIFF BUS_0.22UF
J 2
(-7250 1250);
DISPLAY 0.553191 (-7250 1250);
FORCEPROP 1 LAST CDS_LMAN_SYM_OUTLINE -25,50,25,-50
J 2
(-7100 1250);
DISPLAY 0.468085 (-7100 1250);
PAINT GREEN (-7100 1250);
DISPLAY INVISIBLE (-7100 1250);
FORCEPROP 2 LAST CDS_LIB pure_quanta
J 2
(-7100 1250);
DISPLAY INVISIBLE (-7100 1250);
FORCEPROP 1 LAST PIN_NAMES_ROTATE TRUE
J 2
(-7100 1250);
DISPLAY 0.489362 (-7100 1250);
PAINT GREEN (-7100 1250);
DISPLAY INVISIBLE (-7100 1250);
FORCEPROP 2 LAST VOLTAGE 6.3V
J 2
(-7450 1300);
DISPLAY 0.553191 (-7450 1300);
DISPLAY INVISIBLE (-7450 1300);
FORCEPROP 1 LAST MATERIAL X6S
J 2
(-7091 1329);
DISPLAY 0.574468 (-7091 1329);
PAINT GREEN (-7091 1329);
DISPLAY INVISIBLE (-7091 1329);
FORCEPROP 2 LAST PACK_TYPE C0201
J 2
(-7275 1300);
DISPLAY 0.553191 (-7275 1300);
DISPLAY INVISIBLE (-7275 1300);
FORCEPROP 2 LAST TOLERANCE 20%
J 2
(-7175 1300);
DISPLAY 0.553191 (-7175 1300);
DISPLAY INVISIBLE (-7175 1300);
FORCEPROP 1 LAST PATH I91
J 2
(-7100 1250);
DISPLAY 0.723404 (-7100 1250);
DISPLAY INVISIBLE (-7100 1250);
FORCEPROP 1 LAST PART_NUMBER SP_CH4221MEE01
J 2
(-7216 1338);
DISPLAY 0.574468 (-7216 1338);
PAINT GREEN (-7216 1338);
DISPLAY INVISIBLE (-7216 1338);
FORCEPROP 1 LAST LOCATION C6719
J 0
(-6850 1325);
DISPLAY 1.021277 (-6850 1325);
DISPLAY INVISIBLE (-6850 1325);
FORCEADD Q_CAP_DIFFBUS..2
R 2
(-7100 1400);
FORCEPROP 1 LAST LOCATION C6718
J 2
(-6825 1400);
DISPLAY 0.723404 (-6825 1400);
PAINT GREEN (-6825 1400);
FORCEPROP 2 LAST $SEC 1
J 2
(-6925 1475);
DISPLAY 0.680851 (-6925 1475);
PAINT MONO (-6925 1475);
DISPLAY INVISIBLE (-6925 1475);
FORCEPROP 2 LAST CDS_SEC 1
J 2
(-6925 1475);
DISPLAY 0.680851 (-6925 1475);
DISPLAY INVISIBLE (-6925 1475);
FORCEPROP 2 LASTPIN (-7025 1400) $PN 1
J 0
(-7015 1410);
DISPLAY 0.808511 (-7015 1410);
FORCEPROP 2 LASTPIN (-7175 1400) $PN 2
J 2
(-7185 1410);
DISPLAY 0.808511 (-7185 1410);
FORCEPROP 2 LAST VALUE DIFF BUS_0.22UF
J 2
(-7250 1400);
DISPLAY 0.553191 (-7250 1400);
FORCEPROP 2 LAST CDS_LIB pure_quanta
J 2
(-7100 1400);
DISPLAY INVISIBLE (-7100 1400);
FORCEPROP 1 LAST CDS_LMAN_SYM_OUTLINE -25,50,25,-50
J 2
(-7100 1400);
DISPLAY 0.468085 (-7100 1400);
PAINT GREEN (-7100 1400);
DISPLAY INVISIBLE (-7100 1400);
FORCEPROP 1 LAST PIN_NAMES_ROTATE TRUE
J 2
(-7100 1400);
DISPLAY 0.489362 (-7100 1400);
PAINT GREEN (-7100 1400);
DISPLAY INVISIBLE (-7100 1400);
FORCEPROP 2 LAST VOLTAGE 6.3V
J 2
(-7450 1450);
DISPLAY 0.553191 (-7450 1450);
DISPLAY INVISIBLE (-7450 1450);
FORCEPROP 1 LAST MATERIAL X6S
J 2
(-7091 1479);
DISPLAY 0.574468 (-7091 1479);
PAINT GREEN (-7091 1479);
DISPLAY INVISIBLE (-7091 1479);
FORCEPROP 2 LAST PACK_TYPE C0201
J 2
(-7275 1450);
DISPLAY 0.553191 (-7275 1450);
DISPLAY INVISIBLE (-7275 1450);
FORCEPROP 2 LAST TOLERANCE 20%
J 2
(-7175 1450);
DISPLAY 0.553191 (-7175 1450);
DISPLAY INVISIBLE (-7175 1450);
FORCEPROP 1 LAST PATH I92
J 2
(-7100 1400);
DISPLAY 0.723404 (-7100 1400);
DISPLAY INVISIBLE (-7100 1400);
FORCEPROP 1 LAST PART_NUMBER SP_CH4221MEE01
J 2
(-7216 1488);
DISPLAY 0.574468 (-7216 1488);
PAINT GREEN (-7216 1488);
DISPLAY INVISIBLE (-7216 1488);
FORCEPROP 1 LAST LOCATION C6718
J 0
(-6850 1475);
DISPLAY 1.021277 (-6850 1475);
DISPLAY INVISIBLE (-6850 1475);
FORCEADD Q_CAP_DIFFBUS..2
R 2
(-7100 1450);
FORCEPROP 1 LAST LOCATION C6717
J 2
(-6825 1450);
DISPLAY 0.723404 (-6825 1450);
PAINT GREEN (-6825 1450);
FORCEPROP 2 LAST $SEC 1
J 2
(-6925 1525);
DISPLAY 0.680851 (-6925 1525);
PAINT MONO (-6925 1525);
DISPLAY INVISIBLE (-6925 1525);
FORCEPROP 2 LAST CDS_SEC 1
J 2
(-6925 1525);
DISPLAY 0.680851 (-6925 1525);
DISPLAY INVISIBLE (-6925 1525);
FORCEPROP 2 LASTPIN (-7025 1450) $PN 1
J 0
(-7015 1460);
DISPLAY 0.808511 (-7015 1460);
FORCEPROP 2 LASTPIN (-7175 1450) $PN 2
J 2
(-7185 1460);
DISPLAY 0.808511 (-7185 1460);
FORCEPROP 2 LAST VALUE DIFF BUS_0.22UF
J 2
(-7250 1450);
DISPLAY 0.553191 (-7250 1450);
FORCEPROP 2 LAST CDS_LIB pure_quanta
J 2
(-7100 1450);
DISPLAY INVISIBLE (-7100 1450);
FORCEPROP 1 LAST CDS_LMAN_SYM_OUTLINE -25,50,25,-50
J 2
(-7100 1450);
DISPLAY 0.468085 (-7100 1450);
PAINT GREEN (-7100 1450);
DISPLAY INVISIBLE (-7100 1450);
FORCEPROP 1 LAST PIN_NAMES_ROTATE TRUE
J 2
(-7100 1450);
DISPLAY 0.489362 (-7100 1450);
PAINT GREEN (-7100 1450);
DISPLAY INVISIBLE (-7100 1450);
FORCEPROP 2 LAST VOLTAGE 6.3V
J 2
(-7450 1500);
DISPLAY 0.553191 (-7450 1500);
DISPLAY INVISIBLE (-7450 1500);
FORCEPROP 1 LAST MATERIAL X6S
J 2
(-7091 1529);
DISPLAY 0.574468 (-7091 1529);
PAINT GREEN (-7091 1529);
DISPLAY INVISIBLE (-7091 1529);
FORCEPROP 2 LAST PACK_TYPE C0201
J 2
(-7275 1500);
DISPLAY 0.553191 (-7275 1500);
DISPLAY INVISIBLE (-7275 1500);
FORCEPROP 2 LAST TOLERANCE 20%
J 2
(-7175 1500);
DISPLAY 0.553191 (-7175 1500);
DISPLAY INVISIBLE (-7175 1500);
FORCEPROP 1 LAST PATH I93
J 2
(-7100 1450);
DISPLAY 0.723404 (-7100 1450);
DISPLAY INVISIBLE (-7100 1450);
FORCEPROP 1 LAST PART_NUMBER SP_CH4221MEE01
J 2
(-7216 1538);
DISPLAY 0.574468 (-7216 1538);
PAINT GREEN (-7216 1538);
DISPLAY INVISIBLE (-7216 1538);
FORCEPROP 1 LAST LOCATION C6717
J 0
(-6850 1525);
DISPLAY 1.021277 (-6850 1525);
DISPLAY INVISIBLE (-6850 1525);
FORCEADD Q_CAP_DIFFBUS..2
R 2
(-7100 1600);
FORCEPROP 1 LAST LOCATION C6716
J 2
(-6825 1600);
DISPLAY 0.723404 (-6825 1600);
PAINT GREEN (-6825 1600);
FORCEPROP 2 LAST $SEC 1
J 2
(-6925 1675);
DISPLAY 0.680851 (-6925 1675);
PAINT MONO (-6925 1675);
DISPLAY INVISIBLE (-6925 1675);
FORCEPROP 2 LAST CDS_SEC 1
J 2
(-6925 1675);
DISPLAY 0.680851 (-6925 1675);
DISPLAY INVISIBLE (-6925 1675);
FORCEPROP 2 LASTPIN (-7025 1600) $PN 1
J 0
(-7015 1610);
DISPLAY 0.808511 (-7015 1610);
FORCEPROP 2 LASTPIN (-7175 1600) $PN 2
J 2
(-7185 1610);
DISPLAY 0.808511 (-7185 1610);
FORCEPROP 2 LAST VALUE DIFF BUS_0.22UF
J 2
(-7250 1600);
DISPLAY 0.553191 (-7250 1600);
FORCEPROP 1 LAST CDS_LMAN_SYM_OUTLINE -25,50,25,-50
J 2
(-7100 1600);
DISPLAY 0.468085 (-7100 1600);
PAINT GREEN (-7100 1600);
DISPLAY INVISIBLE (-7100 1600);
FORCEPROP 2 LAST CDS_LIB pure_quanta
J 2
(-7100 1600);
DISPLAY INVISIBLE (-7100 1600);
FORCEPROP 1 LAST PIN_NAMES_ROTATE TRUE
J 2
(-7100 1600);
DISPLAY 0.489362 (-7100 1600);
PAINT GREEN (-7100 1600);
DISPLAY INVISIBLE (-7100 1600);
FORCEPROP 2 LAST VOLTAGE 6.3V
J 2
(-7450 1650);
DISPLAY 0.553191 (-7450 1650);
DISPLAY INVISIBLE (-7450 1650);
FORCEPROP 1 LAST MATERIAL X6S
J 2
(-7091 1679);
DISPLAY 0.574468 (-7091 1679);
PAINT GREEN (-7091 1679);
DISPLAY INVISIBLE (-7091 1679);
FORCEPROP 2 LAST PACK_TYPE C0201
J 2
(-7275 1650);
DISPLAY 0.553191 (-7275 1650);
DISPLAY INVISIBLE (-7275 1650);
FORCEPROP 2 LAST TOLERANCE 20%
J 2
(-7175 1650);
DISPLAY 0.553191 (-7175 1650);
DISPLAY INVISIBLE (-7175 1650);
FORCEPROP 1 LAST PATH I94
J 2
(-7100 1600);
DISPLAY 0.723404 (-7100 1600);
DISPLAY INVISIBLE (-7100 1600);
FORCEPROP 1 LAST PART_NUMBER SP_CH4221MEE01
J 2
(-7216 1688);
DISPLAY 0.574468 (-7216 1688);
PAINT GREEN (-7216 1688);
DISPLAY INVISIBLE (-7216 1688);
FORCEPROP 1 LAST LOCATION C6716
J 0
(-6850 1675);
DISPLAY 1.021277 (-6850 1675);
DISPLAY INVISIBLE (-6850 1675);
FORCEADD Q_CAP_DIFFBUS..2
R 2
(-7100 1650);
FORCEPROP 1 LAST LOCATION C6715
J 2
(-6825 1650);
DISPLAY 0.723404 (-6825 1650);
PAINT GREEN (-6825 1650);
FORCEPROP 2 LAST $SEC 1
J 2
(-6925 1725);
DISPLAY 0.680851 (-6925 1725);
PAINT MONO (-6925 1725);
DISPLAY INVISIBLE (-6925 1725);
FORCEPROP 2 LAST CDS_SEC 1
J 2
(-6925 1725);
DISPLAY 0.680851 (-6925 1725);
DISPLAY INVISIBLE (-6925 1725);
FORCEPROP 2 LASTPIN (-7025 1650) $PN 1
J 0
(-7015 1660);
DISPLAY 0.808511 (-7015 1660);
FORCEPROP 2 LASTPIN (-7175 1650) $PN 2
J 2
(-7185 1660);
DISPLAY 0.808511 (-7185 1660);
FORCEPROP 2 LAST VALUE DIFF BUS_0.22UF
J 2
(-7250 1650);
DISPLAY 0.553191 (-7250 1650);
FORCEPROP 1 LAST CDS_LMAN_SYM_OUTLINE -25,50,25,-50
J 2
(-7100 1650);
DISPLAY 0.468085 (-7100 1650);
PAINT GREEN (-7100 1650);
DISPLAY INVISIBLE (-7100 1650);
FORCEPROP 2 LAST CDS_LIB pure_quanta
J 2
(-7100 1650);
DISPLAY INVISIBLE (-7100 1650);
FORCEPROP 1 LAST PIN_NAMES_ROTATE TRUE
J 2
(-7100 1650);
DISPLAY 0.489362 (-7100 1650);
PAINT GREEN (-7100 1650);
DISPLAY INVISIBLE (-7100 1650);
FORCEPROP 2 LAST VOLTAGE 6.3V
J 2
(-7450 1700);
DISPLAY 0.553191 (-7450 1700);
DISPLAY INVISIBLE (-7450 1700);
FORCEPROP 1 LAST MATERIAL X6S
J 2
(-7091 1729);
DISPLAY 0.574468 (-7091 1729);
PAINT GREEN (-7091 1729);
DISPLAY INVISIBLE (-7091 1729);
FORCEPROP 2 LAST PACK_TYPE C0201
J 2
(-7275 1700);
DISPLAY 0.553191 (-7275 1700);
DISPLAY INVISIBLE (-7275 1700);
FORCEPROP 2 LAST TOLERANCE 20%
J 2
(-7175 1700);
DISPLAY 0.553191 (-7175 1700);
DISPLAY INVISIBLE (-7175 1700);
FORCEPROP 1 LAST PATH I95
J 2
(-7100 1650);
DISPLAY 0.723404 (-7100 1650);
DISPLAY INVISIBLE (-7100 1650);
FORCEPROP 1 LAST PART_NUMBER SP_CH4221MEE01
J 2
(-7216 1738);
DISPLAY 0.574468 (-7216 1738);
PAINT GREEN (-7216 1738);
DISPLAY INVISIBLE (-7216 1738);
FORCEPROP 1 LAST LOCATION C6715
J 0
(-6850 1725);
DISPLAY 1.021277 (-6850 1725);
DISPLAY INVISIBLE (-6850 1725);
FORCEADD Q_CAP_DIFFBUS..2
R 2
(-7100 1800);
FORCEPROP 1 LAST LOCATION C6714
J 2
(-6825 1800);
DISPLAY 0.723404 (-6825 1800);
PAINT GREEN (-6825 1800);
FORCEPROP 2 LAST $SEC 1
J 2
(-6925 1875);
DISPLAY 0.680851 (-6925 1875);
PAINT MONO (-6925 1875);
DISPLAY INVISIBLE (-6925 1875);
FORCEPROP 2 LAST CDS_SEC 1
J 2
(-6925 1875);
DISPLAY 0.680851 (-6925 1875);
DISPLAY INVISIBLE (-6925 1875);
FORCEPROP 2 LASTPIN (-7025 1800) $PN 1
J 0
(-7015 1810);
DISPLAY 0.808511 (-7015 1810);
FORCEPROP 2 LASTPIN (-7175 1800) $PN 2
J 2
(-7185 1810);
DISPLAY 0.808511 (-7185 1810);
FORCEPROP 2 LAST VALUE DIFF BUS_0.22UF
J 2
(-7250 1800);
DISPLAY 0.553191 (-7250 1800);
FORCEPROP 1 LAST CDS_LMAN_SYM_OUTLINE -25,50,25,-50
J 2
(-7100 1800);
DISPLAY 0.468085 (-7100 1800);
PAINT GREEN (-7100 1800);
DISPLAY INVISIBLE (-7100 1800);
FORCEPROP 2 LAST CDS_LIB pure_quanta
J 2
(-7100 1800);
DISPLAY INVISIBLE (-7100 1800);
FORCEPROP 1 LAST PIN_NAMES_ROTATE TRUE
J 2
(-7100 1800);
DISPLAY 0.489362 (-7100 1800);
PAINT GREEN (-7100 1800);
DISPLAY INVISIBLE (-7100 1800);
FORCEPROP 2 LAST VOLTAGE 6.3V
J 2
(-7450 1850);
DISPLAY 0.553191 (-7450 1850);
DISPLAY INVISIBLE (-7450 1850);
FORCEPROP 1 LAST MATERIAL X6S
J 2
(-7091 1879);
DISPLAY 0.574468 (-7091 1879);
PAINT GREEN (-7091 1879);
DISPLAY INVISIBLE (-7091 1879);
FORCEPROP 2 LAST PACK_TYPE C0201
J 2
(-7275 1850);
DISPLAY 0.553191 (-7275 1850);
DISPLAY INVISIBLE (-7275 1850);
FORCEPROP 2 LAST TOLERANCE 20%
J 2
(-7175 1850);
DISPLAY 0.553191 (-7175 1850);
DISPLAY INVISIBLE (-7175 1850);
FORCEPROP 1 LAST PATH I96
J 2
(-7100 1800);
DISPLAY 0.723404 (-7100 1800);
DISPLAY INVISIBLE (-7100 1800);
FORCEPROP 1 LAST PART_NUMBER SP_CH4221MEE01
J 2
(-7216 1888);
DISPLAY 0.574468 (-7216 1888);
PAINT GREEN (-7216 1888);
DISPLAY INVISIBLE (-7216 1888);
FORCEPROP 1 LAST LOCATION C6714
J 0
(-6850 1875);
DISPLAY 1.021277 (-6850 1875);
DISPLAY INVISIBLE (-6850 1875);
FORCEADD Q_CAP_DIFFBUS..2
R 2
(-7100 1850);
FORCEPROP 1 LAST LOCATION C6713
J 2
(-6825 1850);
DISPLAY 0.723404 (-6825 1850);
PAINT GREEN (-6825 1850);
FORCEPROP 2 LAST $SEC 1
J 2
(-6925 1925);
DISPLAY 0.680851 (-6925 1925);
PAINT MONO (-6925 1925);
DISPLAY INVISIBLE (-6925 1925);
FORCEPROP 2 LAST CDS_SEC 1
J 2
(-6925 1925);
DISPLAY 0.680851 (-6925 1925);
DISPLAY INVISIBLE (-6925 1925);
FORCEPROP 2 LASTPIN (-7025 1850) $PN 1
J 0
(-7015 1860);
DISPLAY 0.808511 (-7015 1860);
FORCEPROP 2 LASTPIN (-7175 1850) $PN 2
J 2
(-7185 1860);
DISPLAY 0.808511 (-7185 1860);
FORCEPROP 2 LAST VALUE DIFF BUS_0.22UF
J 2
(-7250 1850);
DISPLAY 0.553191 (-7250 1850);
FORCEPROP 1 LAST CDS_LMAN_SYM_OUTLINE -25,50,25,-50
J 2
(-7100 1850);
DISPLAY 0.468085 (-7100 1850);
PAINT GREEN (-7100 1850);
DISPLAY INVISIBLE (-7100 1850);
FORCEPROP 2 LAST CDS_LIB pure_quanta
J 2
(-7100 1850);
DISPLAY INVISIBLE (-7100 1850);
FORCEPROP 1 LAST PIN_NAMES_ROTATE TRUE
J 2
(-7100 1850);
DISPLAY 0.489362 (-7100 1850);
PAINT GREEN (-7100 1850);
DISPLAY INVISIBLE (-7100 1850);
FORCEPROP 2 LAST VOLTAGE 6.3V
J 2
(-7450 1900);
DISPLAY 0.553191 (-7450 1900);
DISPLAY INVISIBLE (-7450 1900);
FORCEPROP 1 LAST MATERIAL X6S
J 2
(-7091 1929);
DISPLAY 0.574468 (-7091 1929);
PAINT GREEN (-7091 1929);
DISPLAY INVISIBLE (-7091 1929);
FORCEPROP 2 LAST PACK_TYPE C0201
J 2
(-7275 1900);
DISPLAY 0.553191 (-7275 1900);
DISPLAY INVISIBLE (-7275 1900);
FORCEPROP 2 LAST TOLERANCE 20%
J 2
(-7175 1900);
DISPLAY 0.553191 (-7175 1900);
DISPLAY INVISIBLE (-7175 1900);
FORCEPROP 1 LAST PATH I97
J 2
(-7100 1850);
DISPLAY 0.723404 (-7100 1850);
DISPLAY INVISIBLE (-7100 1850);
FORCEPROP 1 LAST PART_NUMBER SP_CH4221MEE01
J 2
(-7216 1938);
DISPLAY 0.574468 (-7216 1938);
PAINT GREEN (-7216 1938);
DISPLAY INVISIBLE (-7216 1938);
FORCEPROP 1 LAST LOCATION C6713
J 0
(-6850 1925);
DISPLAY 1.021277 (-6850 1925);
DISPLAY INVISIBLE (-6850 1925);
FORCEADD Q_CAP_DIFFBUS..2
R 2
(-7100 2000);
FORCEPROP 1 LAST LOCATION C6712
J 2
(-6825 2000);
DISPLAY 0.723404 (-6825 2000);
PAINT GREEN (-6825 2000);
FORCEPROP 2 LAST $SEC 1
J 2
(-6925 2075);
DISPLAY 0.680851 (-6925 2075);
PAINT MONO (-6925 2075);
DISPLAY INVISIBLE (-6925 2075);
FORCEPROP 2 LAST CDS_SEC 1
J 2
(-6925 2075);
DISPLAY 0.680851 (-6925 2075);
DISPLAY INVISIBLE (-6925 2075);
FORCEPROP 2 LASTPIN (-7025 2000) $PN 1
J 0
(-7015 2010);
DISPLAY 0.808511 (-7015 2010);
FORCEPROP 2 LASTPIN (-7175 2000) $PN 2
J 2
(-7185 2010);
DISPLAY 0.808511 (-7185 2010);
FORCEPROP 2 LAST VALUE DIFF BUS_0.22UF
J 2
(-7250 2000);
DISPLAY 0.553191 (-7250 2000);
FORCEPROP 1 LAST CDS_LMAN_SYM_OUTLINE -25,50,25,-50
J 2
(-7100 2000);
DISPLAY 0.468085 (-7100 2000);
PAINT GREEN (-7100 2000);
DISPLAY INVISIBLE (-7100 2000);
FORCEPROP 2 LAST CDS_LIB pure_quanta
J 2
(-7100 2000);
DISPLAY INVISIBLE (-7100 2000);
FORCEPROP 1 LAST PIN_NAMES_ROTATE TRUE
J 2
(-7100 2000);
DISPLAY 0.489362 (-7100 2000);
PAINT GREEN (-7100 2000);
DISPLAY INVISIBLE (-7100 2000);
FORCEPROP 2 LAST VOLTAGE 6.3V
J 2
(-7450 2050);
DISPLAY 0.553191 (-7450 2050);
DISPLAY INVISIBLE (-7450 2050);
FORCEPROP 1 LAST MATERIAL X6S
J 2
(-7091 2079);
DISPLAY 0.574468 (-7091 2079);
PAINT GREEN (-7091 2079);
DISPLAY INVISIBLE (-7091 2079);
FORCEPROP 2 LAST PACK_TYPE C0201
J 2
(-7275 2050);
DISPLAY 0.553191 (-7275 2050);
DISPLAY INVISIBLE (-7275 2050);
FORCEPROP 2 LAST TOLERANCE 20%
J 2
(-7175 2050);
DISPLAY 0.553191 (-7175 2050);
DISPLAY INVISIBLE (-7175 2050);
FORCEPROP 1 LAST PATH I98
J 2
(-7100 2000);
DISPLAY 0.723404 (-7100 2000);
DISPLAY INVISIBLE (-7100 2000);
FORCEPROP 1 LAST PART_NUMBER SP_CH4221MEE01
J 2
(-7216 2088);
DISPLAY 0.574468 (-7216 2088);
PAINT GREEN (-7216 2088);
DISPLAY INVISIBLE (-7216 2088);
FORCEPROP 1 LAST LOCATION C6712
J 0
(-6850 2075);
DISPLAY 1.021277 (-6850 2075);
DISPLAY INVISIBLE (-6850 2075);
FORCEADD Q_CAP_DIFFBUS..2
R 2
(-7100 2050);
FORCEPROP 1 LAST LOCATION C6711
J 2
(-6825 2050);
DISPLAY 0.723404 (-6825 2050);
PAINT GREEN (-6825 2050);
FORCEPROP 2 LAST $SEC 1
J 2
(-6925 2125);
DISPLAY 0.680851 (-6925 2125);
PAINT MONO (-6925 2125);
DISPLAY INVISIBLE (-6925 2125);
FORCEPROP 2 LAST CDS_SEC 1
J 2
(-6925 2125);
DISPLAY 0.680851 (-6925 2125);
DISPLAY INVISIBLE (-6925 2125);
FORCEPROP 2 LASTPIN (-7025 2050) $PN 1
J 0
(-7015 2060);
DISPLAY 0.808511 (-7015 2060);
FORCEPROP 2 LASTPIN (-7175 2050) $PN 2
J 2
(-7185 2060);
DISPLAY 0.808511 (-7185 2060);
FORCEPROP 2 LAST VALUE DIFF BUS_0.22UF
J 2
(-7250 2050);
DISPLAY 0.553191 (-7250 2050);
FORCEPROP 1 LAST CDS_LMAN_SYM_OUTLINE -25,50,25,-50
J 2
(-7100 2050);
DISPLAY 0.468085 (-7100 2050);
PAINT GREEN (-7100 2050);
DISPLAY INVISIBLE (-7100 2050);
FORCEPROP 2 LAST CDS_LIB pure_quanta
J 2
(-7100 2050);
DISPLAY INVISIBLE (-7100 2050);
FORCEPROP 1 LAST PIN_NAMES_ROTATE TRUE
J 2
(-7100 2050);
DISPLAY 0.489362 (-7100 2050);
PAINT GREEN (-7100 2050);
DISPLAY INVISIBLE (-7100 2050);
FORCEPROP 2 LAST VOLTAGE 6.3V
J 2
(-7450 2100);
DISPLAY 0.553191 (-7450 2100);
DISPLAY INVISIBLE (-7450 2100);
FORCEPROP 1 LAST MATERIAL X6S
J 2
(-7091 2129);
DISPLAY 0.574468 (-7091 2129);
PAINT GREEN (-7091 2129);
DISPLAY INVISIBLE (-7091 2129);
FORCEPROP 2 LAST PACK_TYPE C0201
J 2
(-7275 2100);
DISPLAY 0.553191 (-7275 2100);
DISPLAY INVISIBLE (-7275 2100);
FORCEPROP 2 LAST TOLERANCE 20%
J 2
(-7175 2100);
DISPLAY 0.553191 (-7175 2100);
DISPLAY INVISIBLE (-7175 2100);
FORCEPROP 1 LAST PATH I99
J 2
(-7100 2050);
DISPLAY 0.723404 (-7100 2050);
DISPLAY INVISIBLE (-7100 2050);
FORCEPROP 1 LAST PART_NUMBER SP_CH4221MEE01
J 2
(-7216 2138);
DISPLAY 0.574468 (-7216 2138);
PAINT GREEN (-7216 2138);
DISPLAY INVISIBLE (-7216 2138);
FORCEPROP 1 LAST LOCATION C6711
J 0
(-6850 2125);
DISPLAY 1.021277 (-6850 2125);
DISPLAY INVISIBLE (-6850 2125);
FORCEADD QUANTA_TITLE_BLOCK_C..1
(0 0);
FORCEPROP 0 LAST CDS_CON_LAST_MODIFIED Thu Sep 14 16:12:55 2023
J 0
(-1885 15);
DISPLAY INVISIBLE (-1885 15);
FORCEPROP 1 LAST CUSTOM_TXT_CDS <CON_LAST_MODIFIED>
J 0
(-1885 15);
DISPLAY 0.978723 (-1885 15);
FORCEPROP 2 LAST CUSTOM_TXT_CDS <XR_PAGE_TITLE>
J 0
(-7890 5250);
DISPLAY 0.638298 (-7890 5250);
PAINT PINK (-7890 5250);
DISPLAY INVISIBLE (-7890 5250);
FORCEPROP 1 LAST CUSTOM_TXT_CDS <NAME_2>
J 0
(-3175 50);
FORCEPROP 1 LAST CUSTOM_TXT_CDS <NAME_1>
J 0
(-3175 175);
FORCEPROP 1 LAST CUSTOM_TXT_CDS <Q_NUMBER>
J 0
(-1403 103);
DISPLAY 1.212766 (-1403 103);
FORCEPROP 1 LAST CUSTOM_TXT_CDS <Q_PROJ>
J 0
(-2382 102);
DISPLAY 1.212766 (-2382 102);
FORCEPROP 1 LAST CUSTOM_TXT_CDS <Q_REV>
J 0
(-184 103);
DISPLAY 1.212766 (-184 103);
FORCEPROP 1 LAST CUSTOM_TXT_CDS <CON_PAGE_NUM> OF <CON_TOTAL_PAGES>
J 0
(-446 18);
DISPLAY 0.978723 (-446 18);
FORCEPROP 1 LAST Q_TITLE RETIMER_CPU1_P2(4)
J 0
(-9366 26);
DISPLAY 2.446809 (-9366 26);
PAINT GREEN (-9366 26);
FORCEPROP 2 LAST PAGE_BORDER TRUE
J 0
(-7890 5250);
DISPLAY 0.638298 (-7890 5250);
PAINT PINK (-7890 5250);
DISPLAY INVISIBLE (-7890 5250);
FORCEPROP 1 LAST CDS_LMAN_SYM_OUTLINE -9475,6775,100,-125
J 0
(0 0);
DISPLAY 0.468085 (0 0);
PAINT GREEN (0 0);
DISPLAY INVISIBLE (0 0);
FORCEPROP 2 LAST CDS_LIB pure_quanta
J 0
(0 0);
DISPLAY INVISIBLE (0 0);
FORCEPROP 2 LAST CDS_XR_PAGE_TITLE CR-342 : @T6G_MB_LIB.T6G(SCH_1):PAGE342
J 0
(-7890 5250);
DISPLAY 0.638298 (-7890 5250);
PAINT PINK (-7890 5250);
DISPLAY INVISIBLE (-7890 5250);
FORCEPROP 1 LAST Q_DEPT BU9
J 1
(-3763 49);
DISPLAY 1.957447 (-3763 49);
PAINT GREEN (-3763 49);
DISPLAY INVISIBLE (-3763 49);
FORCEPROP 1 LAST COMMENT_BODY TRUE
J 0
(12 -13);
DISPLAY 0.978723 (12 -13);
PAINT GREEN (12 -13);
DISPLAY INVISIBLE (12 -13);
WIRE 17 -1 (-4200 2150)(-3350 2150);
FORCEPROP 2 LAST SIG_NAME P5E_CPU1_P2_TX_BUF_DN<7:0>
J 0
(-4185 2160);
DISPLAY 0.680851 (-4185 2160);
PAINT WHITE (-4185 2160);
WIRE 17 -1 (-1525 1750)(-1525 1550);
WIRE 17 -1 (-1525 1950)(-1525 1750);
WIRE 17 -1 (-1525 1350)(-1525 1550);
WIRE 17 -1 (-1525 1350)(-1525 1150);
WIRE 17 -1 (-1525 2150)(-1525 1950);
FORCEPROP 2 LAST SIG_NAME P5E_CPU1_P2_TX_BUF_C_DN<7:0>
J 0
(-1535 2160);
DISPLAY 0.680851 (-1535 2160);
PAINT WHITE (-1535 2160);
WIRE 17 -1 (-3350 750)(-3350 950);
WIRE 17 -1 (-3350 950)(-3350 1150);
WIRE 17 -1 (-3350 1150)(-3350 1350);
WIRE 17 -1 (-3350 1350)(-3350 1550);
WIRE 17 -1 (-3350 1550)(-3350 1750);
WIRE 17 -1 (-3350 1750)(-3350 1950);
WIRE 17 -1 (-3350 1950)(-3350 2150);
WIRE 17 -1 (-3100 1000)(-3100 800);
WIRE 17 -1 (-3100 1200)(-3100 1000);
WIRE 17 -1 (-3100 1400)(-3100 1200);
WIRE 17 -1 (-3100 1400)(-3100 1600);
WIRE 17 -1 (-3100 1800)(-3100 1600);
WIRE 17 -1 (-3100 2000)(-3100 1800);
WIRE 17 -1 (-3100 2200)(-3100 2000);
WIRE 17 -1 (-4200 2200)(-3100 2200);
FORCEPROP 2 LAST SIG_NAME P5E_CPU1_P2_TX_BUF_DP<7:0>
J 0
(-4185 2210);
DISPLAY 0.680851 (-4185 2210);
PAINT WHITE (-4185 2210);
WIRE 17 -1 (-1525 950)(-1525 750);
WIRE 17 -1 (-1525 1150)(-1525 950);
WIRE 17 -1 (-1725 1000)(-1725 800);
WIRE 17 -1 (-1725 1200)(-1725 1000);
WIRE 17 -1 (-1725 1400)(-1725 1200);
WIRE 17 -1 (-1725 1400)(-1725 1600);
WIRE 17 -1 (-1725 1800)(-1725 1600);
WIRE 17 -1 (-1725 2000)(-1725 1800);
WIRE 17 -1 (-1725 2200)(-1725 2000);
WIRE 17 -1 (-1725 2200)(-625 2200);
FORCEPROP 2 LAST SIG_NAME P5E_CPU1_P2_TX_BUF_C_DP<7:0>
J 0
(-1535 2210);
DISPLAY 0.680851 (-1535 2210);
PAINT WHITE (-1535 2210);
WIRE 17 -1 (-8125 825)(-8125 1025);
WIRE 17 -1 (-8125 1025)(-8125 1225);
WIRE 17 -1 (-8125 1225)(-8125 1425);
WIRE 17 -1 (-8125 1425)(-8125 1625);
WIRE 17 -1 (-8125 1625)(-8125 1825);
WIRE 17 -1 (-8125 1825)(-8125 2025);
WIRE 17 -1 (-8125 2025)(-8125 2225);
WIRE 17 -1 (-8975 2225)(-8125 2225);
FORCEPROP 2 LAST SIG_NAME P5E_CPU1_P2_TX_BUF_DN<15:8>
J 0
(-8960 2235);
DISPLAY 0.680851 (-8960 2235);
PAINT WHITE (-8960 2235);
WIRE 17 -1 (-7875 1075)(-7875 875);
WIRE 17 -1 (-7875 1275)(-7875 1075);
WIRE 17 -1 (-7875 1475)(-7875 1275);
WIRE 17 -1 (-7875 1475)(-7875 1675);
WIRE 17 -1 (-7875 1875)(-7875 1675);
WIRE 17 -1 (-7875 2075)(-7875 1875);
WIRE 17 -1 (-7875 2275)(-7875 2075);
WIRE 17 -1 (-8975 2275)(-7875 2275);
FORCEPROP 2 LAST SIG_NAME P5E_CPU1_P2_TX_BUF_DP<15:8>
J 0
(-8960 2285);
DISPLAY 0.680851 (-8960 2285);
PAINT WHITE (-8960 2285);
WIRE 17 -1 (-6300 1025)(-6300 825);
WIRE 17 -1 (-6300 1225)(-6300 1025);
WIRE 17 -1 (-6300 1425)(-6300 1225);
WIRE 17 -1 (-6300 1425)(-6300 1625);
WIRE 17 -1 (-6300 1825)(-6300 1625);
WIRE 17 -1 (-6300 2025)(-6300 1825);
WIRE 17 -1 (-6300 2225)(-6300 2025);
FORCEPROP 2 LAST SIG_NAME P5E_CPU1_P2_TX_BUF_C_DN<15:8>
J 0
(-6310 2235);
DISPLAY 0.680851 (-6310 2235);
PAINT WHITE (-6310 2235);
WIRE 17 -1 (-6500 1075)(-6500 875);
WIRE 17 -1 (-6500 1275)(-6500 1075);
WIRE 17 -1 (-6500 1475)(-6500 1275);
WIRE 17 -1 (-6500 1475)(-6500 1675);
WIRE 17 -1 (-6500 1875)(-6500 1675);
WIRE 17 -1 (-6500 2075)(-6500 1875);
WIRE 17 -1 (-6500 2275)(-6500 2075);
WIRE 17 -1 (-6500 2275)(-5400 2275);
FORCEPROP 2 LAST SIG_NAME P5E_CPU1_P2_TX_BUF_C_DP<15:8>
J 0
(-6310 2285);
DISPLAY 0.680851 (-6310 2285);
PAINT WHITE (-6310 2285);
WIRE 17 -1 (-6800 3700)(-6800 3350);
WIRE 17 -1 (-6800 4050)(-6800 3700);
WIRE 17 -1 (-6800 4400)(-6800 4050);
WIRE 17 -1 (-6800 4400)(-6800 4750);
WIRE 17 -1 (-6800 5100)(-6800 4750);
WIRE 17 -1 (-6800 5450)(-6800 5100);
WIRE 17 -1 (-6800 5800)(-6800 5450);
FORCEPROP 2 LAST SIG_NAME P5E_CPU1_P2_TX_BUF_DN<15:8>
J 0
(-6810 5810);
DISPLAY 0.680851 (-6810 5810);
PAINT WHITE (-6810 5810);
WIRE 17 -1 (-1625 3675)(-1625 3325);
WIRE 17 -1 (-1625 4025)(-1625 3675);
WIRE 17 -1 (-1625 4375)(-1625 4025);
WIRE 17 -1 (-1625 4375)(-1625 4725);
WIRE 17 -1 (-1625 5075)(-1625 4725);
WIRE 17 -1 (-1625 5425)(-1625 5075);
WIRE 17 -1 (-1625 5775)(-1625 5425);
FORCEPROP 2 LAST SIG_NAME P5E_CPU1_P2_TX_BUF_DN<7:0>
J 0
(-1635 5785);
DISPLAY 0.680851 (-1635 5785);
PAINT WHITE (-1635 5785);
WIRE 17 -1 (-1825 3775)(-1825 3425);
WIRE 17 -1 (-1825 4125)(-1825 3775);
WIRE 17 -1 (-1825 4475)(-1825 4125);
WIRE 17 -1 (-1825 4475)(-1825 4825);
WIRE 17 -1 (-1825 5175)(-1825 4825);
WIRE 17 -1 (-1825 5525)(-1825 5175);
WIRE 17 -1 (-1825 5875)(-1825 5525);
WIRE 17 -1 (-1825 5875)(-725 5875);
FORCEPROP 2 LAST SIG_NAME P5E_CPU1_P2_TX_BUF_DP<7:0>
J 0
(-1635 5885);
DISPLAY 0.680851 (-1635 5885);
PAINT WHITE (-1635 5885);
WIRE 17 -1 (-7000 5550)(-7000 5200);
WIRE 17 -1 (-7000 5900)(-7000 5550);
WIRE 17 -1 (-7000 5200)(-7000 4850);
WIRE 17 -1 (-7000 4500)(-7000 4850);
WIRE 17 -1 (-7000 5900)(-5900 5900);
FORCEPROP 2 LAST SIG_NAME P5E_CPU1_P2_TX_BUF_DP<15:8>
J 0
(-6810 5910);
DISPLAY 0.680851 (-6810 5910);
PAINT WHITE (-6810 5910);
WIRE 17 -1 (-7000 3800)(-7000 3450);
WIRE 17 -1 (-7000 4150)(-7000 3800);
WIRE 17 -1 (-7000 4500)(-7000 4150);
WIRE 17 -1 (-1525 2150)(-625 2150);
WIRE 17 -1 (-6300 2225)(-5400 2225);
WIRE 17 -1 (-6800 5800)(-5925 5800);
WIRE 17 -1 (-1625 5775)(-750 5775);
WIRE 16 -1 (-7325 3775)(-7100 3775);
WIRE 16 -1 (-7325 4125)(-7100 4125);
WIRE 16 -1 (-7325 4025)(-6900 4025);
WIRE 16 -1 (-7325 3675)(-6900 3675);
WIRE 16 -1 (-7325 4825)(-7100 4825);
WIRE 16 -1 (-7325 4375)(-6900 4375);
WIRE 16 -1 (-7325 5525)(-7100 5525);
WIRE 16 -1 (-7325 5875)(-7100 5875);
WIRE 16 -1 (-2150 3750)(-1925 3750);
WIRE 16 -1 (-2150 4450)(-1925 4450);
WIRE 16 -1 (-2150 5150)(-1925 5150);
WIRE 16 -1 (-2150 4800)(-1925 4800);
WIRE 16 -1 (-2150 4350)(-1725 4350);
WIRE 16 -1 (-2150 4700)(-1725 4700);
WIRE 16 -1 (-2150 5850)(-1925 5850);
WIRE 16 -1 (-2150 5750)(-1725 5750);
WIRE 16 -1 (-2150 5400)(-1725 5400);
WIRE 16 -1 (-2150 4100)(-1925 4100);
WIRE 16 -1 (-7325 4475)(-7100 4475);
WIRE 16 -1 (-2150 5500)(-1925 5500);
WIRE 16 -1 (-2150 5050)(-1725 5050);
WIRE 16 -1 (-7325 5775)(-6900 5775);
WIRE 16 -1 (-7325 3425)(-7100 3425);
WIRE 16 -1 (-7325 4725)(-6900 4725);
WIRE 16 -1 (-7325 5075)(-6900 5075);
WIRE 16 -1 (-7325 5175)(-7100 5175);
WIRE 16 -1 (-7325 5425)(-6900 5425);
WIRE 16 -1 (-2150 3400)(-1925 3400);
WIRE 16 -1 (-2150 3650)(-1725 3650);
WIRE 16 -1 (-2150 4000)(-1725 4000);
WIRE 16 -1 (-2150 3300)(-1725 3300);
WIRE 16 -1 (-7325 3325)(-6900 3325);
WIRE 16 -1 (-7025 2250)(-6600 2250);
WIRE 16 -1 (-7025 2200)(-6400 2200);
WIRE 16 -1 (-7175 2250)(-7775 2250);
WIRE 16 -1 (-7175 2200)(-8025 2200);
WIRE 16 -1 (-7025 2050)(-6600 2050);
WIRE 16 -1 (-7025 2000)(-6400 2000);
WIRE 16 -1 (-7025 1850)(-6600 1850);
WIRE 16 -1 (-7025 1800)(-6400 1800);
WIRE 16 -1 (-7025 1650)(-6600 1650);
WIRE 16 -1 (-7025 1600)(-6400 1600);
WIRE 16 -1 (-7025 1450)(-6600 1450);
WIRE 16 -1 (-7025 1400)(-6400 1400);
WIRE 16 -1 (-7025 1250)(-6600 1250);
WIRE 16 -1 (-7025 1200)(-6400 1200);
WIRE 16 -1 (-7025 1050)(-6600 1050);
WIRE 16 -1 (-7025 1000)(-6400 1000);
WIRE 16 -1 (-7025 850)(-6600 850);
WIRE 16 -1 (-7025 800)(-6400 800);
WIRE 16 -1 (-7175 2050)(-7775 2050);
WIRE 16 -1 (-7175 1850)(-7775 1850);
WIRE 16 -1 (-7175 1650)(-7775 1650);
WIRE 16 -1 (-7175 2000)(-8025 2000);
WIRE 16 -1 (-7175 1600)(-8025 1600);
WIRE 16 -1 (-7175 1800)(-8025 1800);
WIRE 16 -1 (-7175 1450)(-7775 1450);
WIRE 16 -1 (-7175 1250)(-7775 1250);
WIRE 16 -1 (-7175 1200)(-8025 1200);
WIRE 16 -1 (-7175 1400)(-8025 1400);
WIRE 16 -1 (-7175 1050)(-7775 1050);
WIRE 16 -1 (-7175 850)(-7775 850);
WIRE 16 -1 (-7175 1000)(-8025 1000);
WIRE 16 -1 (-7175 800)(-8025 800);
WIRE 16 -1 (-2250 2175)(-1825 2175);
WIRE 16 -1 (-2250 2125)(-1625 2125);
WIRE 16 -1 (-2250 1975)(-1825 1975);
WIRE 16 -1 (-2250 1925)(-1625 1925);
WIRE 16 -1 (-2250 1775)(-1825 1775);
WIRE 16 -1 (-2250 1575)(-1825 1575);
WIRE 16 -1 (-2250 1525)(-1625 1525);
WIRE 16 -1 (-2250 1375)(-1825 1375);
WIRE 16 -1 (-2250 1325)(-1625 1325);
WIRE 16 -1 (-2400 2175)(-3000 2175);
WIRE 16 -1 (-2400 1975)(-3000 1975);
WIRE 16 -1 (-2400 1775)(-3000 1775);
WIRE 16 -1 (-2400 1575)(-3000 1575);
WIRE 16 -1 (-2400 1375)(-3000 1375);
WIRE 16 -1 (-2250 1175)(-1825 1175);
WIRE 16 -1 (-2250 1125)(-1625 1125);
WIRE 16 -1 (-2250 975)(-1825 975);
WIRE 16 -1 (-2250 925)(-1625 925);
WIRE 16 -1 (-2250 775)(-1825 775);
WIRE 16 -1 (-2250 725)(-1625 725);
WIRE 16 -1 (-2400 1175)(-3000 1175);
WIRE 16 -1 (-2400 975)(-3000 975);
WIRE 16 -1 (-2400 775)(-3000 775);
WIRE 16 -1 (-2400 1925)(-3250 1925);
WIRE 16 -1 (-2400 1725)(-3250 1725);
WIRE 16 -1 (-2400 1525)(-3250 1525);
WIRE 16 -1 (-2400 1325)(-3250 1325);
WIRE 16 -1 (-2400 1125)(-3250 1125);
WIRE 16 -1 (-2400 925)(-3250 925);
WIRE 16 -1 (-2400 725)(-3250 725);
WIRE 16 -1 (-2250 1725)(-1625 1725);
WIRE 16 -1 (-2400 2125)(-3250 2125);
FORCENOTE
RETIMER TO EXAMAX
(-3675 2950) 0;
DISPLAY LEFT (-3675 2950);
DISPLAY 3.148936 (-3675 2950);
FORCENOTE
RETIMER TO EXAMAX
(-8675 2975) 0;
DISPLAY LEFT (-8675 2975);
DISPLAY 3.148936 (-8675 2975);
FORCENOTE
P5E_CPU1_P2_TX_BUF_DP/DN<0-15> LANE REVERSAL
(-9075 6475) 0;
DISPLAY LEFT (-9075 6475);
DISPLAY 2.000000 (-9075 6475);
QUIT
